FILE_TYPE = MACRO_DRAWING;
SET COLOR_WIRE YELLOW;
SET COLOR_PROP MONO;
SET COLOR_DOT WHITE;
SET COLOR_ARC YELLOW;
SET COLOR_BODY GREEN;
SET COLOR_NOTE MONO;
SET PROP_DISPLAY VALUE;
SET PAGE_NUMBER P45;
FORCEADD OFFPAGE..3
(1600 5200);
FORCEPROP 2 LAST $XR0 24 
J 0
(1814 5200);
DISPLAY 0.638298 (1814 5200);
PAINT MONO (1814 5200);
FORCEPROP 2 LAST $XR1 46 
J 0
(1904 5200);
DISPLAY 0.638298 (1904 5200);
PAINT MONO (1904 5200);
FORCEPROP 2 LAST CDS_LIB mstr_standard
J 0
(1600 5200);
DISPLAY 0.787234 (1600 5200);
PAINT MONO (1600 5200);
DISPLAY INVISIBLE (1600 5200);
FORCEPROP 1 LAST OFFPAGE TRUE
J 0
(1925 5075);
DISPLAY 0.936170 (1925 5075);
PAINT GREEN (1925 5075);
DISPLAY INVISIBLE (1925 5075);
FORCEPROP 1 LAST COMMENT_BODY TRUE
J 0
(1550 5100);
DISPLAY 0.936170 (1550 5100);
PAINT GREEN (1550 5100);
DISPLAY INVISIBLE (1550 5100);
FORCEPROP 2 LAST PATH I1
J 0
(1800 5275);
DISPLAY 0.787234 (1800 5275);
PAINT MONO (1800 5275);
DISPLAY INVISIBLE (1800 5275);
FORCEADD TAP..6
R 2
(700 4850);
FORCEPROP 3 LASTPIN (650 4850) SIG_NAME M_B_DQS_DP<14>
J 0
(660 4860);
DISPLAY 0.659574 (660 4860);
PAINT MONO (660 4860);
DISPLAY INVISIBLE (660 4860);
FORCEPROP 1 LASTPIN (650 4850) BN 14
J 2
(700 4860);
DISPLAY 0.617021 (700 4860);
PAINT PINK (700 4860);
FORCEPROP 2 LAST CDS_LIB mstr_standard
J 0
(700 4850);
DISPLAY 0.787234 (700 4850);
PAINT MONO (700 4850);
DISPLAY INVISIBLE (700 4850);
FORCEPROP 1 LAST BODY_TYPE PLUMBING
J 2
(700 4800);
DISPLAY 1.234043 (700 4800);
PAINT GREEN (700 4800);
DISPLAY INVISIBLE (700 4800);
FORCEPROP 1 LAST HDL_TAP TRUE
J 2
(375 4725);
DISPLAY 1.234043 (375 4725);
PAINT GREEN (375 4725);
DISPLAY INVISIBLE (375 4725);
FORCEPROP 1 LAST PATH I10
J 2
(700 4850);
DISPLAY 0.936170 (700 4850);
PAINT GREEN (700 4850);
DISPLAY INVISIBLE (700 4850);
FORCEADD TAP..6
R 2
(-1700 1850);
FORCEPROP 3 LASTPIN (-1750 1850) SIG_NAME M_B_DQ<9>
J 0
(-1740 1860);
DISPLAY 0.659574 (-1740 1860);
PAINT MONO (-1740 1860);
DISPLAY INVISIBLE (-1740 1860);
FORCEPROP 1 LASTPIN (-1750 1850) BN 9
J 2
(-1700 1860);
DISPLAY 0.617021 (-1700 1860);
PAINT PINK (-1700 1860);
FORCEPROP 2 LAST CDS_LIB mstr_standard
J 2
(-1700 1850);
DISPLAY 0.787234 (-1700 1850);
PAINT MONO (-1700 1850);
DISPLAY INVISIBLE (-1700 1850);
FORCEPROP 1 LAST BODY_TYPE PLUMBING
J 2
(-1700 1800);
DISPLAY 1.234043 (-1700 1800);
PAINT GREEN (-1700 1800);
DISPLAY INVISIBLE (-1700 1800);
FORCEPROP 1 LAST HDL_TAP TRUE
J 2
(-2025 1725);
DISPLAY 1.234043 (-2025 1725);
PAINT GREEN (-2025 1725);
DISPLAY INVISIBLE (-2025 1725);
FORCEPROP 1 LAST PATH I100
J 2
(-1700 1850);
DISPLAY 0.936170 (-1700 1850);
PAINT GREEN (-1700 1850);
DISPLAY INVISIBLE (-1700 1850);
FORCEADD TAP..6
R 2
(-1700 1950);
FORCEPROP 3 LASTPIN (-1750 1950) SIG_NAME M_B_DQ<11>
J 0
(-1740 1960);
DISPLAY 0.659574 (-1740 1960);
PAINT MONO (-1740 1960);
DISPLAY INVISIBLE (-1740 1960);
FORCEPROP 1 LASTPIN (-1750 1950) BN 11
J 2
(-1700 1960);
DISPLAY 0.617021 (-1700 1960);
PAINT PINK (-1700 1960);
FORCEPROP 2 LAST CDS_LIB mstr_standard
J 2
(-1700 1950);
DISPLAY 0.787234 (-1700 1950);
PAINT MONO (-1700 1950);
DISPLAY INVISIBLE (-1700 1950);
FORCEPROP 1 LAST BODY_TYPE PLUMBING
J 2
(-1700 1900);
DISPLAY 1.234043 (-1700 1900);
PAINT GREEN (-1700 1900);
DISPLAY INVISIBLE (-1700 1900);
FORCEPROP 1 LAST HDL_TAP TRUE
J 2
(-2025 1825);
DISPLAY 1.234043 (-2025 1825);
PAINT GREEN (-2025 1825);
DISPLAY INVISIBLE (-2025 1825);
FORCEPROP 1 LAST PATH I101
J 2
(-1700 1950);
DISPLAY 0.936170 (-1700 1950);
PAINT GREEN (-1700 1950);
DISPLAY INVISIBLE (-1700 1950);
FORCEADD TAP..6
R 2
(-1700 1900);
FORCEPROP 3 LASTPIN (-1750 1900) SIG_NAME M_B_DQ<8>
J 0
(-1740 1910);
DISPLAY 0.659574 (-1740 1910);
PAINT MONO (-1740 1910);
DISPLAY INVISIBLE (-1740 1910);
FORCEPROP 1 LASTPIN (-1750 1900) BN 8
J 2
(-1700 1910);
DISPLAY 0.617021 (-1700 1910);
PAINT PINK (-1700 1910);
FORCEPROP 2 LAST CDS_LIB mstr_standard
J 2
(-1700 1900);
DISPLAY 0.787234 (-1700 1900);
PAINT MONO (-1700 1900);
DISPLAY INVISIBLE (-1700 1900);
FORCEPROP 1 LAST BODY_TYPE PLUMBING
J 2
(-1700 1850);
DISPLAY 1.234043 (-1700 1850);
PAINT GREEN (-1700 1850);
DISPLAY INVISIBLE (-1700 1850);
FORCEPROP 1 LAST HDL_TAP TRUE
J 2
(-2025 1775);
DISPLAY 1.234043 (-2025 1775);
PAINT GREEN (-2025 1775);
DISPLAY INVISIBLE (-2025 1775);
FORCEPROP 1 LAST PATH I102
J 2
(-1700 1900);
DISPLAY 0.936170 (-1700 1900);
PAINT GREEN (-1700 1900);
DISPLAY INVISIBLE (-1700 1900);
FORCEADD TAP..6
R 2
(-1700 1700);
FORCEPROP 3 LASTPIN (-1750 1700) SIG_NAME M_B_DQ<4>
J 0
(-1740 1710);
DISPLAY 0.659574 (-1740 1710);
PAINT MONO (-1740 1710);
DISPLAY INVISIBLE (-1740 1710);
FORCEPROP 1 LASTPIN (-1750 1700) BN 4
J 2
(-1700 1710);
DISPLAY 0.617021 (-1700 1710);
PAINT PINK (-1700 1710);
FORCEPROP 2 LAST CDS_LIB mstr_standard
J 2
(-1700 1700);
DISPLAY 0.787234 (-1700 1700);
PAINT MONO (-1700 1700);
DISPLAY INVISIBLE (-1700 1700);
FORCEPROP 1 LAST BODY_TYPE PLUMBING
J 2
(-1700 1650);
DISPLAY 1.234043 (-1700 1650);
PAINT GREEN (-1700 1650);
DISPLAY INVISIBLE (-1700 1650);
FORCEPROP 1 LAST HDL_TAP TRUE
J 2
(-2025 1575);
DISPLAY 1.234043 (-2025 1575);
PAINT GREEN (-2025 1575);
DISPLAY INVISIBLE (-2025 1575);
FORCEPROP 1 LAST PATH I103
J 2
(-1700 1700);
DISPLAY 0.936170 (-1700 1700);
PAINT GREEN (-1700 1700);
DISPLAY INVISIBLE (-1700 1700);
FORCEADD TAP..6
R 2
(-1700 1750);
FORCEPROP 3 LASTPIN (-1750 1750) SIG_NAME M_B_DQ<7>
J 0
(-1740 1760);
DISPLAY 0.659574 (-1740 1760);
PAINT MONO (-1740 1760);
DISPLAY INVISIBLE (-1740 1760);
FORCEPROP 1 LASTPIN (-1750 1750) BN 7
J 2
(-1700 1760);
DISPLAY 0.617021 (-1700 1760);
PAINT PINK (-1700 1760);
FORCEPROP 2 LAST CDS_LIB mstr_standard
J 2
(-1700 1750);
DISPLAY 0.787234 (-1700 1750);
PAINT MONO (-1700 1750);
DISPLAY INVISIBLE (-1700 1750);
FORCEPROP 1 LAST BODY_TYPE PLUMBING
J 2
(-1700 1700);
DISPLAY 1.234043 (-1700 1700);
PAINT GREEN (-1700 1700);
DISPLAY INVISIBLE (-1700 1700);
FORCEPROP 1 LAST HDL_TAP TRUE
J 2
(-2025 1625);
DISPLAY 1.234043 (-2025 1625);
PAINT GREEN (-2025 1625);
DISPLAY INVISIBLE (-2025 1625);
FORCEPROP 1 LAST PATH I104
J 2
(-1700 1750);
DISPLAY 0.936170 (-1700 1750);
PAINT GREEN (-1700 1750);
DISPLAY INVISIBLE (-1700 1750);
FORCEADD TAP..6
R 2
(-1700 1800);
FORCEPROP 3 LASTPIN (-1750 1800) SIG_NAME M_B_DQ<6>
J 0
(-1740 1810);
DISPLAY 0.659574 (-1740 1810);
PAINT MONO (-1740 1810);
DISPLAY INVISIBLE (-1740 1810);
FORCEPROP 1 LASTPIN (-1750 1800) BN 6
J 2
(-1700 1810);
DISPLAY 0.617021 (-1700 1810);
PAINT PINK (-1700 1810);
FORCEPROP 2 LAST CDS_LIB mstr_standard
J 2
(-1700 1800);
DISPLAY 0.787234 (-1700 1800);
PAINT MONO (-1700 1800);
DISPLAY INVISIBLE (-1700 1800);
FORCEPROP 1 LAST BODY_TYPE PLUMBING
J 2
(-1700 1750);
DISPLAY 1.234043 (-1700 1750);
PAINT GREEN (-1700 1750);
DISPLAY INVISIBLE (-1700 1750);
FORCEPROP 1 LAST HDL_TAP TRUE
J 2
(-2025 1675);
DISPLAY 1.234043 (-2025 1675);
PAINT GREEN (-2025 1675);
DISPLAY INVISIBLE (-2025 1675);
FORCEPROP 1 LAST PATH I105
J 2
(-1700 1800);
DISPLAY 0.936170 (-1700 1800);
PAINT GREEN (-1700 1800);
DISPLAY INVISIBLE (-1700 1800);
FORCEADD TAP..6
R 2
(-1700 1650);
FORCEPROP 3 LASTPIN (-1750 1650) SIG_NAME M_B_DQ<5>
J 0
(-1740 1660);
DISPLAY 0.659574 (-1740 1660);
PAINT MONO (-1740 1660);
DISPLAY INVISIBLE (-1740 1660);
FORCEPROP 1 LASTPIN (-1750 1650) BN 5
J 2
(-1700 1660);
DISPLAY 0.617021 (-1700 1660);
PAINT PINK (-1700 1660);
FORCEPROP 2 LAST CDS_LIB mstr_standard
J 2
(-1700 1650);
DISPLAY 0.787234 (-1700 1650);
PAINT MONO (-1700 1650);
DISPLAY INVISIBLE (-1700 1650);
FORCEPROP 1 LAST BODY_TYPE PLUMBING
J 2
(-1700 1600);
DISPLAY 1.234043 (-1700 1600);
PAINT GREEN (-1700 1600);
DISPLAY INVISIBLE (-1700 1600);
FORCEPROP 1 LAST HDL_TAP TRUE
J 2
(-2025 1525);
DISPLAY 1.234043 (-2025 1525);
PAINT GREEN (-2025 1525);
DISPLAY INVISIBLE (-2025 1525);
FORCEPROP 1 LAST PATH I106
J 2
(-1700 1650);
DISPLAY 0.936170 (-1700 1650);
PAINT GREEN (-1700 1650);
DISPLAY INVISIBLE (-1700 1650);
FORCEADD TAP..6
R 2
(-1700 1600);
FORCEPROP 3 LASTPIN (-1750 1600) SIG_NAME M_B_DQ<2>
J 0
(-1740 1610);
DISPLAY 0.659574 (-1740 1610);
PAINT MONO (-1740 1610);
DISPLAY INVISIBLE (-1740 1610);
FORCEPROP 1 LASTPIN (-1750 1600) BN 2
J 2
(-1700 1610);
DISPLAY 0.617021 (-1700 1610);
PAINT PINK (-1700 1610);
FORCEPROP 2 LAST CDS_LIB mstr_standard
J 2
(-1700 1600);
DISPLAY 0.787234 (-1700 1600);
PAINT MONO (-1700 1600);
DISPLAY INVISIBLE (-1700 1600);
FORCEPROP 1 LAST BODY_TYPE PLUMBING
J 2
(-1700 1550);
DISPLAY 1.234043 (-1700 1550);
PAINT GREEN (-1700 1550);
DISPLAY INVISIBLE (-1700 1550);
FORCEPROP 1 LAST HDL_TAP TRUE
J 2
(-2025 1475);
DISPLAY 1.234043 (-2025 1475);
PAINT GREEN (-2025 1475);
DISPLAY INVISIBLE (-2025 1475);
FORCEPROP 1 LAST PATH I107
J 2
(-1700 1600);
DISPLAY 0.936170 (-1700 1600);
PAINT GREEN (-1700 1600);
DISPLAY INVISIBLE (-1700 1600);
FORCEADD TAP..6
R 2
(-1700 1500);
FORCEPROP 3 LASTPIN (-1750 1500) SIG_NAME M_B_DQ<0>
J 0
(-1740 1510);
DISPLAY 0.659574 (-1740 1510);
PAINT MONO (-1740 1510);
DISPLAY INVISIBLE (-1740 1510);
FORCEPROP 1 LASTPIN (-1750 1500) BN 0
J 2
(-1700 1510);
DISPLAY 0.617021 (-1700 1510);
PAINT PINK (-1700 1510);
FORCEPROP 2 LAST CDS_LIB mstr_standard
J 2
(-1700 1500);
DISPLAY 0.787234 (-1700 1500);
PAINT MONO (-1700 1500);
DISPLAY INVISIBLE (-1700 1500);
FORCEPROP 1 LAST BODY_TYPE PLUMBING
J 2
(-1700 1450);
DISPLAY 1.234043 (-1700 1450);
PAINT GREEN (-1700 1450);
DISPLAY INVISIBLE (-1700 1450);
FORCEPROP 1 LAST HDL_TAP TRUE
J 2
(-2025 1375);
DISPLAY 1.234043 (-2025 1375);
PAINT GREEN (-2025 1375);
DISPLAY INVISIBLE (-2025 1375);
FORCEPROP 1 LAST PATH I108
J 2
(-1700 1500);
DISPLAY 0.936170 (-1700 1500);
PAINT GREEN (-1700 1500);
DISPLAY INVISIBLE (-1700 1500);
FORCEADD TAP..6
R 2
(-1700 1550);
FORCEPROP 3 LASTPIN (-1750 1550) SIG_NAME M_B_DQ<3>
J 0
(-1740 1560);
DISPLAY 0.659574 (-1740 1560);
PAINT MONO (-1740 1560);
DISPLAY INVISIBLE (-1740 1560);
FORCEPROP 1 LASTPIN (-1750 1550) BN 3
J 2
(-1700 1560);
DISPLAY 0.617021 (-1700 1560);
PAINT PINK (-1700 1560);
FORCEPROP 2 LAST CDS_LIB mstr_standard
J 2
(-1700 1550);
DISPLAY 0.787234 (-1700 1550);
PAINT MONO (-1700 1550);
DISPLAY INVISIBLE (-1700 1550);
FORCEPROP 1 LAST BODY_TYPE PLUMBING
J 2
(-1700 1500);
DISPLAY 1.234043 (-1700 1500);
PAINT GREEN (-1700 1500);
DISPLAY INVISIBLE (-1700 1500);
FORCEPROP 1 LAST HDL_TAP TRUE
J 2
(-2025 1425);
DISPLAY 1.234043 (-2025 1425);
PAINT GREEN (-2025 1425);
DISPLAY INVISIBLE (-2025 1425);
FORCEPROP 1 LAST PATH I109
J 2
(-1700 1550);
DISPLAY 0.936170 (-1700 1550);
PAINT GREEN (-1700 1550);
DISPLAY INVISIBLE (-1700 1550);
FORCEADD TAP..6
R 2
(-1700 1450);
FORCEPROP 3 LASTPIN (-1750 1450) SIG_NAME M_B_DQ<1>
J 0
(-1740 1460);
DISPLAY 0.659574 (-1740 1460);
PAINT MONO (-1740 1460);
DISPLAY INVISIBLE (-1740 1460);
FORCEPROP 1 LASTPIN (-1750 1450) BN 1
J 2
(-1700 1460);
DISPLAY 0.617021 (-1700 1460);
PAINT PINK (-1700 1460);
FORCEPROP 2 LAST CDS_LIB mstr_standard
J 2
(-1700 1450);
DISPLAY 0.787234 (-1700 1450);
PAINT MONO (-1700 1450);
DISPLAY INVISIBLE (-1700 1450);
FORCEPROP 1 LAST BODY_TYPE PLUMBING
J 2
(-1700 1400);
DISPLAY 1.234043 (-1700 1400);
PAINT GREEN (-1700 1400);
DISPLAY INVISIBLE (-1700 1400);
FORCEPROP 1 LAST HDL_TAP TRUE
J 2
(-2025 1325);
DISPLAY 1.234043 (-2025 1325);
PAINT GREEN (-2025 1325);
DISPLAY INVISIBLE (-2025 1325);
FORCEPROP 1 LAST PATH I110
J 2
(-1700 1450);
DISPLAY 0.936170 (-1700 1450);
PAINT GREEN (-1700 1450);
DISPLAY INVISIBLE (-1700 1450);
FORCEADD SCONN288_H44441004..1
(-2450 2950);
FORCEPROP 1 LAST LOCATION J4G2
J 0
(-2900 4850);
DISPLAY 0.617021 (-2900 4850);
PAINT AQUA (-2900 4850);
FORCEPROP 1 LAST PART_NUMBER H44441-004
J 0
(-2900 950);
DISPLAY 0.617021 (-2900 950);
PAINT BLUE (-2900 950);
FORCEPROP 1 LAST MATERIAL SCONN
J 0
(-2900 4800);
DISPLAY 0.617021 (-2900 4800);
PAINT SKYBLUE (-2900 4800);
FORCEPROP 2 LASTPIN (-2950 1450) $PN 146
J 2
(-2960 1460);
DISPLAY 0.617021 (-2960 1460);
PAINT ORANGE (-2960 1460);
FORCEPROP 2 LASTPIN (-2950 1800) $PN 284
J 2
(-2960 1810);
DISPLAY 0.617021 (-2960 1810);
PAINT ORANGE (-2960 1810);
FORCEPROP 2 LASTPIN (-2950 1600) $PN 285
J 2
(-2960 1610);
DISPLAY 0.617021 (-2960 1610);
PAINT ORANGE (-2960 1610);
FORCEPROP 2 LASTPIN (-2950 1550) $PN 141
J 2
(-2960 1560);
DISPLAY 0.617021 (-2960 1560);
PAINT ORANGE (-2960 1560);
FORCEPROP 2 LASTPIN (-2950 1150) $PN 230
J 2
(-2960 1160);
DISPLAY 0.617021 (-2960 1160);
PAINT ORANGE (-2960 1160);
FORCEPROP 2 LASTPIN (-2950 1750) $PN 238
J 2
(-2960 1760);
DISPLAY 0.617021 (-2960 1760);
PAINT ORANGE (-2960 1760);
FORCEPROP 2 LASTPIN (-2950 1700) $PN 140
J 2
(-2960 1710);
DISPLAY 0.617021 (-2960 1710);
PAINT ORANGE (-2960 1710);
FORCEPROP 2 LASTPIN (-2950 1650) $PN 139
J 2
(-2960 1660);
DISPLAY 0.617021 (-2960 1660);
PAINT ORANGE (-2960 1660);
FORCEPROP 2 LASTPIN (-2950 3100) $PN 237
J 2
(-2960 3110);
DISPLAY 0.617021 (-2960 3110);
PAINT ORANGE (-2960 3110);
FORCEPROP 2 LASTPIN (-2950 3050) $PN 93
J 2
(-2960 3060);
DISPLAY 0.617021 (-2960 3060);
PAINT ORANGE (-2960 3060);
FORCEPROP 2 LASTPIN (-2950 3000) $PN 89
J 2
(-2960 3010);
DISPLAY 0.617021 (-2960 3010);
PAINT ORANGE (-2960 3010);
FORCEPROP 2 LASTPIN (-2950 2950) $PN 84
J 2
(-2960 2960);
DISPLAY 0.617021 (-2960 2960);
PAINT ORANGE (-2960 2960);
FORCEPROP 2 LASTPIN (-2950 1350) $PN 144
J 2
(-2960 1360);
DISPLAY 0.617021 (-2960 1360);
PAINT ORANGE (-2960 1360);
FORCEPROP 2 LASTPIN (-2950 1300) $PN 227
J 2
(-2960 1310);
DISPLAY 0.617021 (-2960 1310);
PAINT ORANGE (-2960 1310);
FORCEPROP 2 LASTPIN (-2950 1250) $PN 205
J 2
(-2960 1260);
DISPLAY 0.617021 (-2960 1260);
PAINT ORANGE (-2960 1260);
FORCEPROP 2 LASTPIN (-2950 2050) $PN 58
J 2
(-2960 2060);
DISPLAY 0.617021 (-2960 2060);
PAINT ORANGE (-2960 2060);
FORCEPROP 2 LASTPIN (-2950 2100) $PN 222
J 2
(-2960 2110);
DISPLAY 0.617021 (-2960 2110);
PAINT ORANGE (-2960 2110);
FORCEPROP 2 LASTPIN (-2950 2700) $PN 91
J 2
(-2960 2710);
DISPLAY 0.617021 (-2960 2710);
PAINT ORANGE (-2960 2710);
FORCEPROP 2 LASTPIN (-2950 2650) $PN 87
J 2
(-2960 2660);
DISPLAY 0.617021 (-2960 2660);
PAINT ORANGE (-2960 2660);
FORCEPROP 2 LASTPIN (-2950 2000) $PN 78
J 2
(-2960 2010);
DISPLAY 0.617021 (-2960 2010);
PAINT ORANGE (-2960 2010);
FORCEPROP 2 LASTPIN (-1950 4600) $PN 280
J 0
(-1940 4610);
DISPLAY 0.617021 (-1940 4610);
PAINT ORANGE (-1940 4610);
FORCEPROP 2 LASTPIN (-1950 4550) $PN 135
J 0
(-1940 4560);
DISPLAY 0.617021 (-1940 4560);
PAINT ORANGE (-1940 4560);
FORCEPROP 2 LASTPIN (-1950 4500) $PN 273
J 0
(-1940 4510);
DISPLAY 0.617021 (-1940 4510);
PAINT ORANGE (-1940 4510);
FORCEPROP 2 LASTPIN (-1950 4450) $PN 128
J 0
(-1940 4460);
DISPLAY 0.617021 (-1940 4460);
PAINT ORANGE (-1940 4460);
FORCEPROP 2 LASTPIN (-1950 4400) $PN 282
J 0
(-1940 4410);
DISPLAY 0.617021 (-1940 4410);
PAINT ORANGE (-1940 4410);
FORCEPROP 2 LASTPIN (-1950 4350) $PN 137
J 0
(-1940 4360);
DISPLAY 0.617021 (-1940 4360);
PAINT ORANGE (-1940 4360);
FORCEPROP 2 LASTPIN (-1950 4300) $PN 275
J 0
(-1940 4310);
DISPLAY 0.617021 (-1940 4310);
PAINT ORANGE (-1940 4310);
FORCEPROP 2 LASTPIN (-1950 4250) $PN 130
J 0
(-1940 4260);
DISPLAY 0.617021 (-1940 4260);
PAINT ORANGE (-1940 4260);
FORCEPROP 2 LASTPIN (-1950 4200) $PN 269
J 0
(-1940 4210);
DISPLAY 0.617021 (-1940 4210);
PAINT ORANGE (-1940 4210);
FORCEPROP 2 LASTPIN (-1950 4150) $PN 124
J 0
(-1940 4160);
DISPLAY 0.617021 (-1940 4160);
PAINT ORANGE (-1940 4160);
FORCEPROP 2 LASTPIN (-1950 4100) $PN 262
J 0
(-1940 4110);
DISPLAY 0.617021 (-1940 4110);
PAINT ORANGE (-1940 4110);
FORCEPROP 2 LASTPIN (-1950 4050) $PN 117
J 0
(-1940 4060);
DISPLAY 0.617021 (-1940 4060);
PAINT ORANGE (-1940 4060);
FORCEPROP 2 LASTPIN (-1950 4000) $PN 271
J 0
(-1940 4010);
DISPLAY 0.617021 (-1940 4010);
PAINT ORANGE (-1940 4010);
FORCEPROP 2 LASTPIN (-1950 3950) $PN 126
J 0
(-1940 3960);
DISPLAY 0.617021 (-1940 3960);
PAINT ORANGE (-1940 3960);
FORCEPROP 2 LASTPIN (-1950 3900) $PN 264
J 0
(-1940 3910);
DISPLAY 0.617021 (-1940 3910);
PAINT ORANGE (-1940 3910);
FORCEPROP 2 LASTPIN (-1950 3850) $PN 119
J 0
(-1940 3860);
DISPLAY 0.617021 (-1940 3860);
PAINT ORANGE (-1940 3860);
FORCEPROP 2 LASTPIN (-1950 3800) $PN 258
J 0
(-1940 3810);
DISPLAY 0.617021 (-1940 3810);
PAINT ORANGE (-1940 3810);
FORCEPROP 2 LASTPIN (-1950 3750) $PN 113
J 0
(-1940 3760);
DISPLAY 0.617021 (-1940 3760);
PAINT ORANGE (-1940 3760);
FORCEPROP 2 LASTPIN (-1950 3700) $PN 251
J 0
(-1940 3710);
DISPLAY 0.617021 (-1940 3710);
PAINT ORANGE (-1940 3710);
FORCEPROP 2 LASTPIN (-1950 3650) $PN 106
J 0
(-1940 3660);
DISPLAY 0.617021 (-1940 3660);
PAINT ORANGE (-1940 3660);
FORCEPROP 2 LASTPIN (-1950 3600) $PN 260
J 0
(-1940 3610);
DISPLAY 0.617021 (-1940 3610);
PAINT ORANGE (-1940 3610);
FORCEPROP 2 LASTPIN (-1950 3550) $PN 115
J 0
(-1940 3560);
DISPLAY 0.617021 (-1940 3560);
PAINT ORANGE (-1940 3560);
FORCEPROP 2 LASTPIN (-1950 3500) $PN 253
J 0
(-1940 3510);
DISPLAY 0.617021 (-1940 3510);
PAINT ORANGE (-1940 3510);
FORCEPROP 2 LASTPIN (-1950 3450) $PN 108
J 0
(-1940 3460);
DISPLAY 0.617021 (-1940 3460);
PAINT ORANGE (-1940 3460);
FORCEPROP 2 LASTPIN (-1950 3400) $PN 247
J 0
(-1940 3410);
DISPLAY 0.617021 (-1940 3410);
PAINT ORANGE (-1940 3410);
FORCEPROP 2 LASTPIN (-1950 3350) $PN 102
J 0
(-1940 3360);
DISPLAY 0.617021 (-1940 3360);
PAINT ORANGE (-1940 3360);
FORCEPROP 2 LASTPIN (-1950 3300) $PN 240
J 0
(-1940 3310);
DISPLAY 0.617021 (-1940 3310);
PAINT ORANGE (-1940 3310);
FORCEPROP 2 LASTPIN (-1950 3250) $PN 95
J 0
(-1940 3260);
DISPLAY 0.617021 (-1940 3260);
PAINT ORANGE (-1940 3260);
FORCEPROP 2 LASTPIN (-1950 3200) $PN 249
J 0
(-1940 3210);
DISPLAY 0.617021 (-1940 3210);
PAINT ORANGE (-1940 3210);
FORCEPROP 2 LASTPIN (-1950 3150) $PN 104
J 0
(-1940 3160);
DISPLAY 0.617021 (-1940 3160);
PAINT ORANGE (-1940 3160);
FORCEPROP 2 LASTPIN (-1950 3100) $PN 242
J 0
(-1940 3110);
DISPLAY 0.617021 (-1940 3110);
PAINT ORANGE (-1940 3110);
FORCEPROP 2 LASTPIN (-1950 3050) $PN 97
J 0
(-1940 3060);
DISPLAY 0.617021 (-1940 3060);
PAINT ORANGE (-1940 3060);
FORCEPROP 2 LASTPIN (-1950 3000) $PN 188
J 0
(-1940 3010);
DISPLAY 0.617021 (-1940 3010);
PAINT ORANGE (-1940 3010);
FORCEPROP 2 LASTPIN (-1950 2950) $PN 43
J 0
(-1940 2960);
DISPLAY 0.617021 (-1940 2960);
PAINT ORANGE (-1940 2960);
FORCEPROP 2 LASTPIN (-1950 2900) $PN 181
J 0
(-1940 2910);
DISPLAY 0.617021 (-1940 2910);
PAINT ORANGE (-1940 2910);
FORCEPROP 2 LASTPIN (-1950 2850) $PN 36
J 0
(-1940 2860);
DISPLAY 0.617021 (-1940 2860);
PAINT ORANGE (-1940 2860);
FORCEPROP 2 LASTPIN (-1950 2800) $PN 190
J 0
(-1940 2810);
DISPLAY 0.617021 (-1940 2810);
PAINT ORANGE (-1940 2810);
FORCEPROP 2 LASTPIN (-1950 2750) $PN 45
J 0
(-1940 2760);
DISPLAY 0.617021 (-1940 2760);
PAINT ORANGE (-1940 2760);
FORCEPROP 2 LASTPIN (-1950 2700) $PN 183
J 0
(-1940 2710);
DISPLAY 0.617021 (-1940 2710);
PAINT ORANGE (-1940 2710);
FORCEPROP 2 LASTPIN (-1950 2650) $PN 38
J 0
(-1940 2660);
DISPLAY 0.617021 (-1940 2660);
PAINT ORANGE (-1940 2660);
FORCEPROP 2 LASTPIN (-1950 2600) $PN 177
J 0
(-1940 2610);
DISPLAY 0.617021 (-1940 2610);
PAINT ORANGE (-1940 2610);
FORCEPROP 2 LASTPIN (-1950 2550) $PN 32
J 0
(-1940 2560);
DISPLAY 0.617021 (-1940 2560);
PAINT ORANGE (-1940 2560);
FORCEPROP 2 LASTPIN (-1950 2500) $PN 170
J 0
(-1940 2510);
DISPLAY 0.617021 (-1940 2510);
PAINT ORANGE (-1940 2510);
FORCEPROP 2 LASTPIN (-1950 2450) $PN 25
J 0
(-1940 2460);
DISPLAY 0.617021 (-1940 2460);
PAINT ORANGE (-1940 2460);
FORCEPROP 2 LASTPIN (-1950 2400) $PN 179
J 0
(-1940 2410);
DISPLAY 0.617021 (-1940 2410);
PAINT ORANGE (-1940 2410);
FORCEPROP 2 LASTPIN (-1950 2350) $PN 34
J 0
(-1940 2360);
DISPLAY 0.617021 (-1940 2360);
PAINT ORANGE (-1940 2360);
FORCEPROP 2 LASTPIN (-1950 2300) $PN 172
J 0
(-1940 2310);
DISPLAY 0.617021 (-1940 2310);
PAINT ORANGE (-1940 2310);
FORCEPROP 2 LASTPIN (-1950 2250) $PN 27
J 0
(-1940 2260);
DISPLAY 0.617021 (-1940 2260);
PAINT ORANGE (-1940 2260);
FORCEPROP 2 LASTPIN (-1950 2200) $PN 166
J 0
(-1940 2210);
DISPLAY 0.617021 (-1940 2210);
PAINT ORANGE (-1940 2210);
FORCEPROP 2 LASTPIN (-1950 2150) $PN 21
J 0
(-1940 2160);
DISPLAY 0.617021 (-1940 2160);
PAINT ORANGE (-1940 2160);
FORCEPROP 2 LASTPIN (-1950 2100) $PN 159
J 0
(-1940 2110);
DISPLAY 0.617021 (-1940 2110);
PAINT ORANGE (-1940 2110);
FORCEPROP 2 LASTPIN (-1950 2050) $PN 14
J 0
(-1940 2060);
DISPLAY 0.617021 (-1940 2060);
PAINT ORANGE (-1940 2060);
FORCEPROP 2 LASTPIN (-1950 2000) $PN 168
J 0
(-1940 2010);
DISPLAY 0.617021 (-1940 2010);
PAINT ORANGE (-1940 2010);
FORCEPROP 2 LASTPIN (-1950 1950) $PN 23
J 0
(-1940 1960);
DISPLAY 0.617021 (-1940 1960);
PAINT ORANGE (-1940 1960);
FORCEPROP 2 LASTPIN (-1950 1900) $PN 161
J 0
(-1940 1910);
DISPLAY 0.617021 (-1940 1910);
PAINT ORANGE (-1940 1910);
FORCEPROP 2 LASTPIN (-1950 1850) $PN 16
J 0
(-1940 1860);
DISPLAY 0.617021 (-1940 1860);
PAINT ORANGE (-1940 1860);
FORCEPROP 2 LASTPIN (-1950 1800) $PN 155
J 0
(-1940 1810);
DISPLAY 0.617021 (-1940 1810);
PAINT ORANGE (-1940 1810);
FORCEPROP 2 LASTPIN (-1950 1750) $PN 10
J 0
(-1940 1760);
DISPLAY 0.617021 (-1940 1760);
PAINT ORANGE (-1940 1760);
FORCEPROP 2 LASTPIN (-1950 1700) $PN 148
J 0
(-1940 1710);
DISPLAY 0.617021 (-1940 1710);
PAINT ORANGE (-1940 1710);
FORCEPROP 2 LASTPIN (-1950 1650) $PN 3
J 0
(-1940 1660);
DISPLAY 0.617021 (-1940 1660);
PAINT ORANGE (-1940 1660);
FORCEPROP 2 LASTPIN (-1950 1600) $PN 157
J 0
(-1940 1610);
DISPLAY 0.617021 (-1940 1610);
PAINT ORANGE (-1940 1610);
FORCEPROP 2 LASTPIN (-1950 1550) $PN 12
J 0
(-1940 1560);
DISPLAY 0.617021 (-1940 1560);
PAINT ORANGE (-1940 1560);
FORCEPROP 2 LASTPIN (-1950 1500) $PN 150
J 0
(-1940 1510);
DISPLAY 0.617021 (-1940 1510);
PAINT ORANGE (-1940 1510);
FORCEPROP 2 LASTPIN (-1950 1450) $PN 5
J 0
(-1940 1460);
DISPLAY 0.617021 (-1940 1460);
PAINT ORANGE (-1940 1460);
FORCEPROP 2 LASTPIN (-2950 2850) $PN 203
J 2
(-2960 2860);
DISPLAY 0.617021 (-2960 2860);
PAINT ORANGE (-2960 2860);
FORCEPROP 2 LASTPIN (-2950 2800) $PN 60
J 2
(-2960 2810);
DISPLAY 0.617021 (-2960 2810);
PAINT ORANGE (-2960 2810);
FORCEPROP 2 LASTPIN (-2950 3400) $PN 218
J 2
(-2960 3410);
DISPLAY 0.617021 (-2960 3410);
PAINT ORANGE (-2960 3410);
FORCEPROP 2 LASTPIN (-2950 3350) $PN 219
J 2
(-2960 3360);
DISPLAY 0.617021 (-2960 3360);
PAINT ORANGE (-2960 3360);
FORCEPROP 2 LASTPIN (-2950 3300) $PN 74
J 2
(-2960 3310);
DISPLAY 0.617021 (-2960 3310);
PAINT ORANGE (-2960 3310);
FORCEPROP 2 LASTPIN (-2950 3250) $PN 75
J 2
(-2960 3260);
DISPLAY 0.617021 (-2960 3260);
PAINT ORANGE (-2960 3260);
FORCEPROP 2 LASTPIN (-2950 2550) $PN 199
J 2
(-2960 2560);
DISPLAY 0.617021 (-2960 2560);
PAINT ORANGE (-2960 2560);
FORCEPROP 2 LASTPIN (-2950 2500) $PN 54
J 2
(-2960 2510);
DISPLAY 0.617021 (-2960 2510);
PAINT ORANGE (-2960 2510);
FORCEPROP 2 LASTPIN (-2950 2450) $PN 192
J 2
(-2960 2460);
DISPLAY 0.617021 (-2960 2460);
PAINT ORANGE (-2960 2460);
FORCEPROP 2 LASTPIN (-2950 2400) $PN 47
J 2
(-2960 2410);
DISPLAY 0.617021 (-2960 2410);
PAINT ORANGE (-2960 2410);
FORCEPROP 2 LASTPIN (-2950 2350) $PN 201
J 2
(-2960 2360);
DISPLAY 0.617021 (-2960 2360);
PAINT ORANGE (-2960 2360);
FORCEPROP 2 LASTPIN (-2950 2300) $PN 56
J 2
(-2960 2310);
DISPLAY 0.617021 (-2960 2310);
PAINT ORANGE (-2960 2310);
FORCEPROP 2 LASTPIN (-2950 2250) $PN 194
J 2
(-2960 2260);
DISPLAY 0.617021 (-2960 2260);
PAINT ORANGE (-2960 2260);
FORCEPROP 2 LASTPIN (-2950 2200) $PN 49
J 2
(-2960 2210);
DISPLAY 0.617021 (-2960 2210);
PAINT ORANGE (-2960 2210);
FORCEPROP 2 LASTPIN (-2950 3150) $PN 235
J 2
(-2960 3160);
DISPLAY 0.617021 (-2960 3160);
PAINT ORANGE (-2960 3160);
FORCEPROP 2 LASTPIN (-2950 3550) $PN 207
J 2
(-2960 3560);
DISPLAY 0.617021 (-2960 3560);
PAINT ORANGE (-2960 3560);
FORCEPROP 2 LASTPIN (-2950 3500) $PN 63
J 2
(-2960 3510);
DISPLAY 0.617021 (-2960 3510);
PAINT ORANGE (-2960 3510);
FORCEPROP 2 LASTPIN (-2950 3650) $PN 224
J 2
(-2960 3660);
DISPLAY 0.617021 (-2960 3660);
PAINT ORANGE (-2960 3660);
FORCEPROP 2 LASTPIN (-2950 3600) $PN 81
J 2
(-2960 3610);
DISPLAY 0.617021 (-2960 3610);
PAINT ORANGE (-2960 3610);
FORCEPROP 2 LASTPIN (-2950 1950) $PN 208
J 2
(-2960 1960);
DISPLAY 0.617021 (-2960 1960);
PAINT ORANGE (-2960 1960);
FORCEPROP 2 LASTPIN (-2950 1900) $PN 62
J 2
(-2960 1910);
DISPLAY 0.617021 (-2960 1910);
PAINT ORANGE (-2960 1910);
FORCEPROP 2 LASTPIN (-2950 4600) $PN 234
J 2
(-2960 4610);
DISPLAY 0.617021 (-2960 4610);
PAINT ORANGE (-2960 4610);
FORCEPROP 2 LASTPIN (-2950 4550) $PN 82
J 2
(-2960 4560);
DISPLAY 0.617021 (-2960 4560);
PAINT ORANGE (-2960 4560);
FORCEPROP 2 LASTPIN (-2950 4500) $PN 86
J 2
(-2960 4510);
DISPLAY 0.617021 (-2960 4510);
PAINT ORANGE (-2960 4510);
FORCEPROP 2 LASTPIN (-2950 4450) $PN 228
J 2
(-2960 4460);
DISPLAY 0.617021 (-2960 4460);
PAINT ORANGE (-2960 4460);
FORCEPROP 2 LASTPIN (-2950 4400) $PN 232
J 2
(-2960 4410);
DISPLAY 0.617021 (-2960 4410);
PAINT ORANGE (-2960 4410);
FORCEPROP 2 LASTPIN (-2950 4350) $PN 65
J 2
(-2960 4360);
DISPLAY 0.617021 (-2960 4360);
PAINT ORANGE (-2960 4360);
FORCEPROP 2 LASTPIN (-2950 4300) $PN 210
J 2
(-2960 4310);
DISPLAY 0.617021 (-2960 4310);
PAINT ORANGE (-2960 4310);
FORCEPROP 2 LASTPIN (-2950 4250) $PN 225
J 2
(-2960 4260);
DISPLAY 0.617021 (-2960 4260);
PAINT ORANGE (-2960 4260);
FORCEPROP 2 LASTPIN (-2950 4200) $PN 66
J 2
(-2960 4210);
DISPLAY 0.617021 (-2960 4210);
PAINT ORANGE (-2960 4210);
FORCEPROP 2 LASTPIN (-2950 4150) $PN 68
J 2
(-2960 4160);
DISPLAY 0.617021 (-2960 4160);
PAINT ORANGE (-2960 4160);
FORCEPROP 2 LASTPIN (-2950 4100) $PN 211
J 2
(-2960 4110);
DISPLAY 0.617021 (-2960 4110);
PAINT ORANGE (-2960 4110);
FORCEPROP 2 LASTPIN (-2950 4050) $PN 69
J 2
(-2960 4060);
DISPLAY 0.617021 (-2960 4060);
PAINT ORANGE (-2960 4060);
FORCEPROP 2 LASTPIN (-2950 4000) $PN 213
J 2
(-2960 4010);
DISPLAY 0.617021 (-2960 4010);
PAINT ORANGE (-2960 4010);
FORCEPROP 2 LASTPIN (-2950 3950) $PN 214
J 2
(-2960 3960);
DISPLAY 0.617021 (-2960 3960);
PAINT ORANGE (-2960 3960);
FORCEPROP 2 LASTPIN (-2950 3900) $PN 71
J 2
(-2960 3910);
DISPLAY 0.617021 (-2960 3910);
PAINT ORANGE (-2960 3910);
FORCEPROP 2 LASTPIN (-2950 3850) $PN 216
J 2
(-2960 3860);
DISPLAY 0.617021 (-2960 3860);
PAINT ORANGE (-2960 3860);
FORCEPROP 2 LASTPIN (-2950 3800) $PN 72
J 2
(-2960 3810);
DISPLAY 0.617021 (-2960 3810);
PAINT ORANGE (-2960 3810);
FORCEPROP 2 LASTPIN (-2950 3750) $PN 79
J 2
(-2960 3760);
DISPLAY 0.617021 (-2960 3760);
PAINT ORANGE (-2960 3760);
FORCEPROP 1 LAST PACK_TYPE PIP
J 0
(-2900 4900);
PAINT SKYBLUE (-2900 4900);
DISPLAY INVISIBLE (-2900 4900);
FORCEPROP 2 LAST BOM_COST MEM
J 0
(-2450 2950);
PAINT ORANGE (-2450 2950);
DISPLAY INVISIBLE (-2450 2950);
FORCEPROP 2 LAST CDS_LIB mstr_sconn
J 0
(-2450 2950);
PAINT ORANGE (-2450 2950);
DISPLAY INVISIBLE (-2450 2950);
FORCEPROP 2 LAST SEC_TYPE PIP
J 0
(-2900 4900);
DISPLAY 1.021277 (-2900 4900);
PAINT ORANGE (-2900 4900);
DISPLAY INVISIBLE (-2900 4900);
FORCEPROP 2 LAST SEC 1
J 0
(-2900 4900);
DISPLAY 0.680851 (-2900 4900);
PAINT MONO (-2900 4900);
DISPLAY INVISIBLE (-2900 4900);
FORCEPROP 2 LAST CDS_LOCATION J4G2
J 0
(-2900 4850);
DISPLAY 0.617021 (-2900 4850);
PAINT AQUA (-2900 4850);
DISPLAY INVISIBLE (-2900 4850);
FORCEPROP 1 LAST PATH I111
J 0
(-2450 4800);
PAINT GREEN (-2450 4800);
DISPLAY INVISIBLE (-2450 4800);
FORCEPROP 2 LAST ROOM DDR4_CH_B
J 0
(-2450 2950);
PAINT ORANGE (-2450 2950);
DISPLAY INVISIBLE (-2450 2950);
FORCEADD TAP..6
(-3200 4600);
FORCEPROP 3 LASTPIN (-3150 4600) SIG_NAME M_B_MA<17>
J 0
(-3140 4610);
DISPLAY 0.659574 (-3140 4610);
PAINT MONO (-3140 4610);
DISPLAY INVISIBLE (-3140 4610);
FORCEPROP 1 LASTPIN (-3150 4600) BN 17
J 0
(-3200 4610);
DISPLAY 0.617021 (-3200 4610);
PAINT PINK (-3200 4610);
FORCEPROP 2 LAST CDS_LIB mstr_standard
J 0
(-3200 4600);
DISPLAY 0.787234 (-3200 4600);
PAINT MONO (-3200 4600);
DISPLAY INVISIBLE (-3200 4600);
FORCEPROP 1 LAST BODY_TYPE PLUMBING
J 0
(-3200 4550);
DISPLAY 1.234043 (-3200 4550);
PAINT GREEN (-3200 4550);
DISPLAY INVISIBLE (-3200 4550);
FORCEPROP 1 LAST HDL_TAP TRUE
J 0
(-2875 4475);
DISPLAY 1.234043 (-2875 4475);
PAINT GREEN (-2875 4475);
DISPLAY INVISIBLE (-2875 4475);
FORCEPROP 1 LAST PATH I112
J 0
(-3200 4600);
DISPLAY 0.936170 (-3200 4600);
PAINT GREEN (-3200 4600);
DISPLAY INVISIBLE (-3200 4600);
FORCEADD TAP..6
(-3200 4550);
FORCEPROP 3 LASTPIN (-3150 4550) SIG_NAME M_B_MA<16>
J 0
(-3140 4560);
DISPLAY 0.659574 (-3140 4560);
PAINT MONO (-3140 4560);
DISPLAY INVISIBLE (-3140 4560);
FORCEPROP 1 LASTPIN (-3150 4550) BN 16
J 0
(-3200 4560);
DISPLAY 0.617021 (-3200 4560);
PAINT PINK (-3200 4560);
FORCEPROP 2 LAST CDS_LIB mstr_standard
J 2
(-3200 4550);
DISPLAY 0.787234 (-3200 4550);
PAINT MONO (-3200 4550);
DISPLAY INVISIBLE (-3200 4550);
FORCEPROP 1 LAST BODY_TYPE PLUMBING
J 0
(-3200 4500);
DISPLAY 1.234043 (-3200 4500);
PAINT GREEN (-3200 4500);
DISPLAY INVISIBLE (-3200 4500);
FORCEPROP 1 LAST HDL_TAP TRUE
J 0
(-2875 4425);
DISPLAY 1.234043 (-2875 4425);
PAINT GREEN (-2875 4425);
DISPLAY INVISIBLE (-2875 4425);
FORCEPROP 1 LAST PATH I113
J 0
(-3200 4550);
DISPLAY 0.936170 (-3200 4550);
PAINT GREEN (-3200 4550);
DISPLAY INVISIBLE (-3200 4550);
FORCEADD TAP..6
(-3200 4500);
FORCEPROP 3 LASTPIN (-3150 4500) SIG_NAME M_B_MA<15>
J 0
(-3140 4510);
DISPLAY 0.659574 (-3140 4510);
PAINT MONO (-3140 4510);
DISPLAY INVISIBLE (-3140 4510);
FORCEPROP 1 LASTPIN (-3150 4500) BN 15
J 0
(-3200 4510);
DISPLAY 0.617021 (-3200 4510);
PAINT PINK (-3200 4510);
FORCEPROP 2 LAST CDS_LIB mstr_standard
J 2
(-3200 4500);
DISPLAY 0.787234 (-3200 4500);
PAINT MONO (-3200 4500);
DISPLAY INVISIBLE (-3200 4500);
FORCEPROP 1 LAST BODY_TYPE PLUMBING
J 0
(-3200 4450);
DISPLAY 1.234043 (-3200 4450);
PAINT GREEN (-3200 4450);
DISPLAY INVISIBLE (-3200 4450);
FORCEPROP 1 LAST HDL_TAP TRUE
J 0
(-2875 4375);
DISPLAY 1.234043 (-2875 4375);
PAINT GREEN (-2875 4375);
DISPLAY INVISIBLE (-2875 4375);
FORCEPROP 1 LAST PATH I114
J 0
(-3200 4500);
DISPLAY 0.936170 (-3200 4500);
PAINT GREEN (-3200 4500);
DISPLAY INVISIBLE (-3200 4500);
FORCEADD TAP..6
(-3200 4450);
FORCEPROP 3 LASTPIN (-3150 4450) SIG_NAME M_B_MA<14>
J 0
(-3140 4460);
DISPLAY 0.659574 (-3140 4460);
PAINT MONO (-3140 4460);
DISPLAY INVISIBLE (-3140 4460);
FORCEPROP 1 LASTPIN (-3150 4450) BN 14
J 0
(-3200 4460);
DISPLAY 0.617021 (-3200 4460);
PAINT PINK (-3200 4460);
FORCEPROP 2 LAST CDS_LIB mstr_standard
J 2
(-3200 4450);
DISPLAY 0.787234 (-3200 4450);
PAINT MONO (-3200 4450);
DISPLAY INVISIBLE (-3200 4450);
FORCEPROP 1 LAST BODY_TYPE PLUMBING
J 0
(-3200 4400);
DISPLAY 1.234043 (-3200 4400);
PAINT GREEN (-3200 4400);
DISPLAY INVISIBLE (-3200 4400);
FORCEPROP 1 LAST HDL_TAP TRUE
J 0
(-2875 4325);
DISPLAY 1.234043 (-2875 4325);
PAINT GREEN (-2875 4325);
DISPLAY INVISIBLE (-2875 4325);
FORCEPROP 1 LAST PATH I115
J 0
(-3200 4450);
DISPLAY 0.936170 (-3200 4450);
PAINT GREEN (-3200 4450);
DISPLAY INVISIBLE (-3200 4450);
FORCEADD TAP..6
(-3200 4400);
FORCEPROP 3 LASTPIN (-3150 4400) SIG_NAME M_B_MA<13>
J 0
(-3140 4410);
DISPLAY 0.659574 (-3140 4410);
PAINT MONO (-3140 4410);
DISPLAY INVISIBLE (-3140 4410);
FORCEPROP 1 LASTPIN (-3150 4400) BN 13
J 0
(-3200 4410);
DISPLAY 0.617021 (-3200 4410);
PAINT PINK (-3200 4410);
FORCEPROP 2 LAST CDS_LIB mstr_standard
J 2
(-3200 4400);
DISPLAY 0.787234 (-3200 4400);
PAINT MONO (-3200 4400);
DISPLAY INVISIBLE (-3200 4400);
FORCEPROP 1 LAST BODY_TYPE PLUMBING
J 0
(-3200 4350);
DISPLAY 1.234043 (-3200 4350);
PAINT GREEN (-3200 4350);
DISPLAY INVISIBLE (-3200 4350);
FORCEPROP 1 LAST HDL_TAP TRUE
J 0
(-2875 4275);
DISPLAY 1.234043 (-2875 4275);
PAINT GREEN (-2875 4275);
DISPLAY INVISIBLE (-2875 4275);
FORCEPROP 1 LAST PATH I116
J 0
(-3200 4400);
DISPLAY 0.936170 (-3200 4400);
PAINT GREEN (-3200 4400);
DISPLAY INVISIBLE (-3200 4400);
FORCEADD TAP..6
(-3200 4350);
FORCEPROP 3 LASTPIN (-3150 4350) SIG_NAME M_B_MA<12>
J 0
(-3140 4360);
DISPLAY 0.659574 (-3140 4360);
PAINT MONO (-3140 4360);
DISPLAY INVISIBLE (-3140 4360);
FORCEPROP 1 LASTPIN (-3150 4350) BN 12
J 0
(-3200 4360);
DISPLAY 0.617021 (-3200 4360);
PAINT PINK (-3200 4360);
FORCEPROP 2 LAST CDS_LIB mstr_standard
J 2
(-3200 4350);
DISPLAY 0.787234 (-3200 4350);
PAINT MONO (-3200 4350);
DISPLAY INVISIBLE (-3200 4350);
FORCEPROP 1 LAST BODY_TYPE PLUMBING
J 0
(-3200 4300);
DISPLAY 1.234043 (-3200 4300);
PAINT GREEN (-3200 4300);
DISPLAY INVISIBLE (-3200 4300);
FORCEPROP 1 LAST HDL_TAP TRUE
J 0
(-2875 4225);
DISPLAY 1.234043 (-2875 4225);
PAINT GREEN (-2875 4225);
DISPLAY INVISIBLE (-2875 4225);
FORCEPROP 1 LAST PATH I117
J 0
(-3200 4350);
DISPLAY 0.936170 (-3200 4350);
PAINT GREEN (-3200 4350);
DISPLAY INVISIBLE (-3200 4350);
FORCEADD TAP..6
(-3200 4300);
FORCEPROP 3 LASTPIN (-3150 4300) SIG_NAME M_B_MA<11>
J 0
(-3140 4310);
DISPLAY 0.659574 (-3140 4310);
PAINT MONO (-3140 4310);
DISPLAY INVISIBLE (-3140 4310);
FORCEPROP 1 LASTPIN (-3150 4300) BN 11
J 0
(-3200 4310);
DISPLAY 0.617021 (-3200 4310);
PAINT PINK (-3200 4310);
FORCEPROP 2 LAST CDS_LIB mstr_standard
J 2
(-3200 4300);
DISPLAY 0.787234 (-3200 4300);
PAINT MONO (-3200 4300);
DISPLAY INVISIBLE (-3200 4300);
FORCEPROP 1 LAST BODY_TYPE PLUMBING
J 0
(-3200 4250);
DISPLAY 1.234043 (-3200 4250);
PAINT GREEN (-3200 4250);
DISPLAY INVISIBLE (-3200 4250);
FORCEPROP 1 LAST HDL_TAP TRUE
J 0
(-2875 4175);
DISPLAY 1.234043 (-2875 4175);
PAINT GREEN (-2875 4175);
DISPLAY INVISIBLE (-2875 4175);
FORCEPROP 1 LAST PATH I118
J 0
(-3200 4300);
DISPLAY 0.936170 (-3200 4300);
PAINT GREEN (-3200 4300);
DISPLAY INVISIBLE (-3200 4300);
FORCEADD TAP..6
(-3200 4250);
FORCEPROP 3 LASTPIN (-3150 4250) SIG_NAME M_B_MA<10>
J 0
(-3140 4260);
DISPLAY 0.659574 (-3140 4260);
PAINT MONO (-3140 4260);
DISPLAY INVISIBLE (-3140 4260);
FORCEPROP 1 LASTPIN (-3150 4250) BN 10
J 0
(-3200 4260);
DISPLAY 0.617021 (-3200 4260);
PAINT PINK (-3200 4260);
FORCEPROP 2 LAST CDS_LIB mstr_standard
J 2
(-3200 4250);
DISPLAY 0.787234 (-3200 4250);
PAINT MONO (-3200 4250);
DISPLAY INVISIBLE (-3200 4250);
FORCEPROP 1 LAST BODY_TYPE PLUMBING
J 0
(-3200 4200);
DISPLAY 1.234043 (-3200 4200);
PAINT GREEN (-3200 4200);
DISPLAY INVISIBLE (-3200 4200);
FORCEPROP 1 LAST HDL_TAP TRUE
J 0
(-2875 4125);
DISPLAY 1.234043 (-2875 4125);
PAINT GREEN (-2875 4125);
DISPLAY INVISIBLE (-2875 4125);
FORCEPROP 1 LAST PATH I119
J 0
(-3200 4250);
DISPLAY 0.936170 (-3200 4250);
PAINT GREEN (-3200 4250);
DISPLAY INVISIBLE (-3200 4250);
FORCEADD PVTT_ABC..1
(-800 2700);
FORCEPROP 3 LASTPIN (-800 2650) SIG_NAME PVTT_ABC\g
J 0
(-790 2660);
DISPLAY 0.659574 (-790 2660);
PAINT MONO (-790 2660);
DISPLAY INVISIBLE (-790 2660);
FORCEPROP 1 LAST VOLTAGE 0.6V
J 0
(-845 2657);
DISPLAY 0.340426 (-845 2657);
PAINT SKYBLUE (-845 2657);
DISPLAY INVISIBLE (-845 2657);
FORCEPROP 2 LAST BOM_COST MEM
J 0
(-800 2705);
PAINT ORANGE (-800 2705);
DISPLAY INVISIBLE (-800 2705);
FORCEPROP 2 LAST CDS_LIB mstr_symbols
J 0
(-800 2700);
PAINT ORANGE (-800 2700);
DISPLAY INVISIBLE (-800 2700);
FORCEPROP 1 LAST BODY_TYPE PLUMBING
J 0
(-845 2657);
DISPLAY 0.340426 (-845 2657);
PAINT GREEN (-845 2657);
DISPLAY INVISIBLE (-845 2657);
FORCEPROP 1 LAST PATH I12
J 0
(-750 2725);
DISPLAY 0.872340 (-750 2725);
PAINT AQUA (-750 2725);
DISPLAY INVISIBLE (-750 2725);
FORCEPROP 2 LAST ROOM DDR4_CH_A
J 0
(-800 2800);
DISPLAY 0.787234 (-800 2800);
PAINT ORANGE (-800 2800);
DISPLAY INVISIBLE (-800 2800);
FORCEPROP 1 LAST HDL_POWER PVTT_ABC
J 1
(-800 2750);
DISPLAY 0.872340 (-800 2750);
PAINT GREEN (-800 2750);
DISPLAY INVISIBLE (-800 2750);
FORCEADD TAP..6
(-3200 4200);
FORCEPROP 3 LASTPIN (-3150 4200) SIG_NAME M_B_MA<9>
J 0
(-3140 4210);
DISPLAY 0.659574 (-3140 4210);
PAINT MONO (-3140 4210);
DISPLAY INVISIBLE (-3140 4210);
FORCEPROP 1 LASTPIN (-3150 4200) BN 9
J 0
(-3200 4210);
DISPLAY 0.617021 (-3200 4210);
PAINT PINK (-3200 4210);
FORCEPROP 2 LAST CDS_LIB mstr_standard
J 2
(-3200 4200);
DISPLAY 0.787234 (-3200 4200);
PAINT MONO (-3200 4200);
DISPLAY INVISIBLE (-3200 4200);
FORCEPROP 1 LAST BODY_TYPE PLUMBING
J 0
(-3200 4150);
DISPLAY 1.234043 (-3200 4150);
PAINT GREEN (-3200 4150);
DISPLAY INVISIBLE (-3200 4150);
FORCEPROP 1 LAST HDL_TAP TRUE
J 0
(-2875 4075);
DISPLAY 1.234043 (-2875 4075);
PAINT GREEN (-2875 4075);
DISPLAY INVISIBLE (-2875 4075);
FORCEPROP 1 LAST PATH I120
J 0
(-3200 4200);
DISPLAY 0.936170 (-3200 4200);
PAINT GREEN (-3200 4200);
DISPLAY INVISIBLE (-3200 4200);
FORCEADD TAP..6
(-3200 4150);
FORCEPROP 3 LASTPIN (-3150 4150) SIG_NAME M_B_MA<8>
J 0
(-3140 4160);
DISPLAY 0.659574 (-3140 4160);
PAINT MONO (-3140 4160);
DISPLAY INVISIBLE (-3140 4160);
FORCEPROP 1 LASTPIN (-3150 4150) BN 8
J 0
(-3200 4160);
DISPLAY 0.617021 (-3200 4160);
PAINT PINK (-3200 4160);
FORCEPROP 2 LAST CDS_LIB mstr_standard
J 2
(-3200 4150);
DISPLAY 0.787234 (-3200 4150);
PAINT MONO (-3200 4150);
DISPLAY INVISIBLE (-3200 4150);
FORCEPROP 1 LAST BODY_TYPE PLUMBING
J 0
(-3200 4100);
DISPLAY 1.234043 (-3200 4100);
PAINT GREEN (-3200 4100);
DISPLAY INVISIBLE (-3200 4100);
FORCEPROP 1 LAST HDL_TAP TRUE
J 0
(-2875 4025);
DISPLAY 1.234043 (-2875 4025);
PAINT GREEN (-2875 4025);
DISPLAY INVISIBLE (-2875 4025);
FORCEPROP 1 LAST PATH I121
J 0
(-3200 4150);
DISPLAY 0.936170 (-3200 4150);
PAINT GREEN (-3200 4150);
DISPLAY INVISIBLE (-3200 4150);
FORCEADD TAP..6
(-3200 4100);
FORCEPROP 3 LASTPIN (-3150 4100) SIG_NAME M_B_MA<7>
J 0
(-3140 4110);
DISPLAY 0.659574 (-3140 4110);
PAINT MONO (-3140 4110);
DISPLAY INVISIBLE (-3140 4110);
FORCEPROP 1 LASTPIN (-3150 4100) BN 7
J 0
(-3200 4110);
DISPLAY 0.617021 (-3200 4110);
PAINT PINK (-3200 4110);
FORCEPROP 2 LAST CDS_LIB mstr_standard
J 2
(-3200 4100);
DISPLAY 0.787234 (-3200 4100);
PAINT MONO (-3200 4100);
DISPLAY INVISIBLE (-3200 4100);
FORCEPROP 1 LAST BODY_TYPE PLUMBING
J 0
(-3200 4050);
DISPLAY 1.234043 (-3200 4050);
PAINT GREEN (-3200 4050);
DISPLAY INVISIBLE (-3200 4050);
FORCEPROP 1 LAST HDL_TAP TRUE
J 0
(-2875 3975);
DISPLAY 1.234043 (-2875 3975);
PAINT GREEN (-2875 3975);
DISPLAY INVISIBLE (-2875 3975);
FORCEPROP 1 LAST PATH I122
J 0
(-3200 4100);
DISPLAY 0.936170 (-3200 4100);
PAINT GREEN (-3200 4100);
DISPLAY INVISIBLE (-3200 4100);
FORCEADD TAP..6
(-3200 4050);
FORCEPROP 3 LASTPIN (-3150 4050) SIG_NAME M_B_MA<6>
J 0
(-3140 4060);
DISPLAY 0.659574 (-3140 4060);
PAINT MONO (-3140 4060);
DISPLAY INVISIBLE (-3140 4060);
FORCEPROP 1 LASTPIN (-3150 4050) BN 6
J 0
(-3200 4060);
DISPLAY 0.617021 (-3200 4060);
PAINT PINK (-3200 4060);
FORCEPROP 2 LAST CDS_LIB mstr_standard
J 2
(-3200 4050);
DISPLAY 0.787234 (-3200 4050);
PAINT MONO (-3200 4050);
DISPLAY INVISIBLE (-3200 4050);
FORCEPROP 1 LAST BODY_TYPE PLUMBING
J 0
(-3200 4000);
DISPLAY 1.234043 (-3200 4000);
PAINT GREEN (-3200 4000);
DISPLAY INVISIBLE (-3200 4000);
FORCEPROP 1 LAST HDL_TAP TRUE
J 0
(-2875 3925);
DISPLAY 1.234043 (-2875 3925);
PAINT GREEN (-2875 3925);
DISPLAY INVISIBLE (-2875 3925);
FORCEPROP 1 LAST PATH I123
J 0
(-3200 4050);
DISPLAY 0.936170 (-3200 4050);
PAINT GREEN (-3200 4050);
DISPLAY INVISIBLE (-3200 4050);
FORCEADD TAP..6
(-3200 4000);
FORCEPROP 3 LASTPIN (-3150 4000) SIG_NAME M_B_MA<5>
J 0
(-3140 4010);
DISPLAY 0.659574 (-3140 4010);
PAINT MONO (-3140 4010);
DISPLAY INVISIBLE (-3140 4010);
FORCEPROP 1 LASTPIN (-3150 4000) BN 5
J 0
(-3200 4010);
DISPLAY 0.617021 (-3200 4010);
PAINT PINK (-3200 4010);
FORCEPROP 2 LAST CDS_LIB mstr_standard
J 2
(-3200 4000);
DISPLAY 0.787234 (-3200 4000);
PAINT MONO (-3200 4000);
DISPLAY INVISIBLE (-3200 4000);
FORCEPROP 1 LAST BODY_TYPE PLUMBING
J 0
(-3200 3950);
DISPLAY 1.234043 (-3200 3950);
PAINT GREEN (-3200 3950);
DISPLAY INVISIBLE (-3200 3950);
FORCEPROP 1 LAST HDL_TAP TRUE
J 0
(-2875 3875);
DISPLAY 1.234043 (-2875 3875);
PAINT GREEN (-2875 3875);
DISPLAY INVISIBLE (-2875 3875);
FORCEPROP 1 LAST PATH I124
J 0
(-3200 4000);
DISPLAY 0.936170 (-3200 4000);
PAINT GREEN (-3200 4000);
DISPLAY INVISIBLE (-3200 4000);
FORCEADD TAP..6
(-3200 3950);
FORCEPROP 3 LASTPIN (-3150 3950) SIG_NAME M_B_MA<4>
J 0
(-3140 3960);
DISPLAY 0.659574 (-3140 3960);
PAINT MONO (-3140 3960);
DISPLAY INVISIBLE (-3140 3960);
FORCEPROP 1 LASTPIN (-3150 3950) BN 4
J 0
(-3200 3960);
DISPLAY 0.617021 (-3200 3960);
PAINT PINK (-3200 3960);
FORCEPROP 2 LAST CDS_LIB mstr_standard
J 2
(-3200 3950);
DISPLAY 0.787234 (-3200 3950);
PAINT MONO (-3200 3950);
DISPLAY INVISIBLE (-3200 3950);
FORCEPROP 1 LAST BODY_TYPE PLUMBING
J 0
(-3200 3900);
DISPLAY 1.234043 (-3200 3900);
PAINT GREEN (-3200 3900);
DISPLAY INVISIBLE (-3200 3900);
FORCEPROP 1 LAST HDL_TAP TRUE
J 0
(-2875 3825);
DISPLAY 1.234043 (-2875 3825);
PAINT GREEN (-2875 3825);
DISPLAY INVISIBLE (-2875 3825);
FORCEPROP 1 LAST PATH I125
J 0
(-3200 3950);
DISPLAY 0.936170 (-3200 3950);
PAINT GREEN (-3200 3950);
DISPLAY INVISIBLE (-3200 3950);
FORCEADD TAP..6
(-3200 3900);
FORCEPROP 3 LASTPIN (-3150 3900) SIG_NAME M_B_MA<3>
J 0
(-3140 3910);
DISPLAY 0.659574 (-3140 3910);
PAINT MONO (-3140 3910);
DISPLAY INVISIBLE (-3140 3910);
FORCEPROP 1 LASTPIN (-3150 3900) BN 3
J 0
(-3200 3910);
DISPLAY 0.617021 (-3200 3910);
PAINT PINK (-3200 3910);
FORCEPROP 2 LAST CDS_LIB mstr_standard
J 2
(-3200 3900);
DISPLAY 0.787234 (-3200 3900);
PAINT MONO (-3200 3900);
DISPLAY INVISIBLE (-3200 3900);
FORCEPROP 1 LAST BODY_TYPE PLUMBING
J 0
(-3200 3850);
DISPLAY 1.234043 (-3200 3850);
PAINT GREEN (-3200 3850);
DISPLAY INVISIBLE (-3200 3850);
FORCEPROP 1 LAST HDL_TAP TRUE
J 0
(-2875 3775);
DISPLAY 1.234043 (-2875 3775);
PAINT GREEN (-2875 3775);
DISPLAY INVISIBLE (-2875 3775);
FORCEPROP 1 LAST PATH I126
J 0
(-3200 3900);
DISPLAY 0.936170 (-3200 3900);
PAINT GREEN (-3200 3900);
DISPLAY INVISIBLE (-3200 3900);
FORCEADD OFFPAGE..1
(-3850 4650);
FORCEPROP 2 LAST $XR0 24 
J 0
(-4101 4650);
DISPLAY 0.638298 (-4101 4650);
PAINT MONO (-4101 4650);
FORCEPROP 2 LAST $XR1 46 
J 0
(-4191 4650);
DISPLAY 0.638298 (-4191 4650);
PAINT MONO (-4191 4650);
FORCEPROP 2 LAST CDS_LIB mstr_standard
J 0
(-3850 4650);
DISPLAY 0.787234 (-3850 4650);
PAINT MONO (-3850 4650);
DISPLAY INVISIBLE (-3850 4650);
FORCEPROP 1 LAST OFFPAGE TRUE
J 0
(-3525 4525);
DISPLAY 0.936170 (-3525 4525);
PAINT GREEN (-3525 4525);
DISPLAY INVISIBLE (-3525 4525);
FORCEPROP 1 LAST COMMENT_BODY TRUE
J 0
(-3725 4550);
DISPLAY 0.936170 (-3725 4550);
PAINT GREEN (-3725 4550);
DISPLAY INVISIBLE (-3725 4550);
FORCEPROP 2 LAST PATH I127
J 0
(-3800 4725);
DISPLAY 0.787234 (-3800 4725);
PAINT MONO (-3800 4725);
DISPLAY INVISIBLE (-3800 4725);
FORCEADD TAP..6
(-3200 3850);
FORCEPROP 3 LASTPIN (-3150 3850) SIG_NAME M_B_MA<2>
J 0
(-3140 3860);
DISPLAY 0.659574 (-3140 3860);
PAINT MONO (-3140 3860);
DISPLAY INVISIBLE (-3140 3860);
FORCEPROP 1 LASTPIN (-3150 3850) BN 2
J 0
(-3200 3860);
DISPLAY 0.617021 (-3200 3860);
PAINT PINK (-3200 3860);
FORCEPROP 2 LAST CDS_LIB mstr_standard
J 2
(-3200 3850);
DISPLAY 0.787234 (-3200 3850);
PAINT MONO (-3200 3850);
DISPLAY INVISIBLE (-3200 3850);
FORCEPROP 1 LAST BODY_TYPE PLUMBING
J 0
(-3200 3800);
DISPLAY 1.234043 (-3200 3800);
PAINT GREEN (-3200 3800);
DISPLAY INVISIBLE (-3200 3800);
FORCEPROP 1 LAST HDL_TAP TRUE
J 0
(-2875 3725);
DISPLAY 1.234043 (-2875 3725);
PAINT GREEN (-2875 3725);
DISPLAY INVISIBLE (-2875 3725);
FORCEPROP 1 LAST PATH I128
J 0
(-3200 3850);
DISPLAY 0.936170 (-3200 3850);
PAINT GREEN (-3200 3850);
DISPLAY INVISIBLE (-3200 3850);
FORCEADD TAP..6
(-3200 3800);
FORCEPROP 3 LASTPIN (-3150 3800) SIG_NAME M_B_MA<1>
J 0
(-3140 3810);
DISPLAY 0.659574 (-3140 3810);
PAINT MONO (-3140 3810);
DISPLAY INVISIBLE (-3140 3810);
FORCEPROP 1 LASTPIN (-3150 3800) BN 1
J 0
(-3200 3810);
DISPLAY 0.617021 (-3200 3810);
PAINT PINK (-3200 3810);
FORCEPROP 2 LAST CDS_LIB mstr_standard
J 2
(-3200 3800);
DISPLAY 0.787234 (-3200 3800);
PAINT MONO (-3200 3800);
DISPLAY INVISIBLE (-3200 3800);
FORCEPROP 1 LAST BODY_TYPE PLUMBING
J 0
(-3200 3750);
DISPLAY 1.234043 (-3200 3750);
PAINT GREEN (-3200 3750);
DISPLAY INVISIBLE (-3200 3750);
FORCEPROP 1 LAST HDL_TAP TRUE
J 0
(-2875 3675);
DISPLAY 1.234043 (-2875 3675);
PAINT GREEN (-2875 3675);
DISPLAY INVISIBLE (-2875 3675);
FORCEPROP 1 LAST PATH I129
J 0
(-3200 3800);
DISPLAY 0.936170 (-3200 3800);
PAINT GREEN (-3200 3800);
DISPLAY INVISIBLE (-3200 3800);
FORCEADD PVDDQ_ABC..1
(-1025 2550);
FORCEPROP 3 LASTPIN (-1025 2500) SIG_NAME PVDDQ_ABC\g
J 0
(-1015 2510);
DISPLAY 0.659574 (-1015 2510);
PAINT MONO (-1015 2510);
DISPLAY INVISIBLE (-1015 2510);
FORCEPROP 1 LAST VOLTAGE 1.2V
J 0
(-1070 2507);
DISPLAY 0.340426 (-1070 2507);
PAINT SKYBLUE (-1070 2507);
DISPLAY INVISIBLE (-1070 2507);
FORCEPROP 2 LAST BOM_COST MEM
J 0
(-1025 2555);
PAINT ORANGE (-1025 2555);
DISPLAY INVISIBLE (-1025 2555);
FORCEPROP 2 LAST CDS_LIB mstr_symbols
J 0
(-1025 2550);
PAINT ORANGE (-1025 2550);
DISPLAY INVISIBLE (-1025 2550);
FORCEPROP 1 LAST BODY_TYPE PLUMBING
J 0
(-1070 2507);
DISPLAY 0.340426 (-1070 2507);
PAINT GREEN (-1070 2507);
DISPLAY INVISIBLE (-1070 2507);
FORCEPROP 1 LAST PATH I13
J 0
(-975 2575);
DISPLAY 0.872340 (-975 2575);
PAINT AQUA (-975 2575);
DISPLAY INVISIBLE (-975 2575);
FORCEPROP 2 LAST ROOM DDR4_CH_A
J 0
(-1025 2650);
DISPLAY 0.787234 (-1025 2650);
PAINT ORANGE (-1025 2650);
DISPLAY INVISIBLE (-1025 2650);
FORCEPROP 1 LAST HDL_POWER PVDDQ_ABC
J 1
(-1025 2600);
DISPLAY 0.872340 (-1025 2600);
PAINT GREEN (-1025 2600);
DISPLAY INVISIBLE (-1025 2600);
FORCEADD TAP..6
(-3200 3750);
FORCEPROP 3 LASTPIN (-3150 3750) SIG_NAME M_B_MA<0>
J 0
(-3140 3760);
DISPLAY 0.659574 (-3140 3760);
PAINT MONO (-3140 3760);
DISPLAY INVISIBLE (-3140 3760);
FORCEPROP 1 LASTPIN (-3150 3750) BN 0
J 0
(-3200 3760);
DISPLAY 0.617021 (-3200 3760);
PAINT PINK (-3200 3760);
FORCEPROP 2 LAST CDS_LIB mstr_standard
J 2
(-3200 3750);
DISPLAY 0.787234 (-3200 3750);
PAINT MONO (-3200 3750);
DISPLAY INVISIBLE (-3200 3750);
FORCEPROP 1 LAST BODY_TYPE PLUMBING
J 0
(-3200 3700);
DISPLAY 1.234043 (-3200 3700);
PAINT GREEN (-3200 3700);
DISPLAY INVISIBLE (-3200 3700);
FORCEPROP 1 LAST HDL_TAP TRUE
J 0
(-2875 3625);
DISPLAY 1.234043 (-2875 3625);
PAINT GREEN (-2875 3625);
DISPLAY INVISIBLE (-2875 3625);
FORCEPROP 1 LAST PATH I130
J 0
(-3200 3750);
DISPLAY 0.936170 (-3200 3750);
PAINT GREEN (-3200 3750);
DISPLAY INVISIBLE (-3200 3750);
FORCEADD TAP..6
(-3200 3650);
FORCEPROP 3 LASTPIN (-3150 3650) SIG_NAME M_B_BA<1>
J 0
(-3140 3660);
DISPLAY 0.659574 (-3140 3660);
PAINT MONO (-3140 3660);
DISPLAY INVISIBLE (-3140 3660);
FORCEPROP 1 LASTPIN (-3150 3650) BN 1
J 0
(-3200 3660);
DISPLAY 0.617021 (-3200 3660);
PAINT PINK (-3200 3660);
FORCEPROP 2 LAST CDS_LIB mstr_standard
J 0
(-3200 3650);
DISPLAY 0.787234 (-3200 3650);
PAINT MONO (-3200 3650);
DISPLAY INVISIBLE (-3200 3650);
FORCEPROP 1 LAST BODY_TYPE PLUMBING
J 0
(-3200 3600);
DISPLAY 1.234043 (-3200 3600);
PAINT GREEN (-3200 3600);
DISPLAY INVISIBLE (-3200 3600);
FORCEPROP 1 LAST HDL_TAP TRUE
J 0
(-2875 3525);
DISPLAY 1.234043 (-2875 3525);
PAINT GREEN (-2875 3525);
DISPLAY INVISIBLE (-2875 3525);
FORCEPROP 1 LAST PATH I131
J 0
(-3200 3650);
DISPLAY 0.936170 (-3200 3650);
PAINT GREEN (-3200 3650);
DISPLAY INVISIBLE (-3200 3650);
FORCEADD TAP..6
(-3200 3600);
FORCEPROP 3 LASTPIN (-3150 3600) SIG_NAME M_B_BA<0>
J 0
(-3140 3610);
DISPLAY 0.659574 (-3140 3610);
PAINT MONO (-3140 3610);
DISPLAY INVISIBLE (-3140 3610);
FORCEPROP 1 LASTPIN (-3150 3600) BN 0
J 0
(-3200 3610);
DISPLAY 0.617021 (-3200 3610);
PAINT PINK (-3200 3610);
FORCEPROP 2 LAST CDS_LIB mstr_standard
J 0
(-3200 3600);
DISPLAY 0.787234 (-3200 3600);
PAINT MONO (-3200 3600);
DISPLAY INVISIBLE (-3200 3600);
FORCEPROP 1 LAST BODY_TYPE PLUMBING
J 0
(-3200 3550);
DISPLAY 1.234043 (-3200 3550);
PAINT GREEN (-3200 3550);
DISPLAY INVISIBLE (-3200 3550);
FORCEPROP 1 LAST HDL_TAP TRUE
J 0
(-2875 3475);
DISPLAY 1.234043 (-2875 3475);
PAINT GREEN (-2875 3475);
DISPLAY INVISIBLE (-2875 3475);
FORCEPROP 1 LAST PATH I132
J 0
(-3200 3600);
DISPLAY 0.936170 (-3200 3600);
PAINT GREEN (-3200 3600);
DISPLAY INVISIBLE (-3200 3600);
FORCEADD TAP..6
(-3200 3500);
FORCEPROP 3 LASTPIN (-3150 3500) SIG_NAME M_B_BG<0>
J 0
(-3140 3510);
DISPLAY 0.659574 (-3140 3510);
PAINT MONO (-3140 3510);
DISPLAY INVISIBLE (-3140 3510);
FORCEPROP 1 LASTPIN (-3150 3500) BN 0
J 0
(-3200 3510);
DISPLAY 0.617021 (-3200 3510);
PAINT PINK (-3200 3510);
FORCEPROP 2 LAST CDS_LIB mstr_standard
J 0
(-3200 3500);
DISPLAY 0.787234 (-3200 3500);
PAINT MONO (-3200 3500);
DISPLAY INVISIBLE (-3200 3500);
FORCEPROP 1 LAST BODY_TYPE PLUMBING
J 0
(-3200 3450);
DISPLAY 1.234043 (-3200 3450);
PAINT GREEN (-3200 3450);
DISPLAY INVISIBLE (-3200 3450);
FORCEPROP 1 LAST HDL_TAP TRUE
J 0
(-2875 3375);
DISPLAY 1.234043 (-2875 3375);
PAINT GREEN (-2875 3375);
DISPLAY INVISIBLE (-2875 3375);
FORCEPROP 1 LAST PATH I133
J 0
(-3200 3500);
DISPLAY 0.936170 (-3200 3500);
PAINT GREEN (-3200 3500);
DISPLAY INVISIBLE (-3200 3500);
FORCEADD TAP..6
(-3200 3550);
FORCEPROP 3 LASTPIN (-3150 3550) SIG_NAME M_B_BG<1>
J 0
(-3140 3560);
DISPLAY 0.659574 (-3140 3560);
PAINT MONO (-3140 3560);
DISPLAY INVISIBLE (-3140 3560);
FORCEPROP 1 LASTPIN (-3150 3550) BN 1
J 0
(-3200 3560);
DISPLAY 0.617021 (-3200 3560);
PAINT PINK (-3200 3560);
FORCEPROP 2 LAST CDS_LIB mstr_standard
J 0
(-3200 3550);
DISPLAY 0.787234 (-3200 3550);
PAINT MONO (-3200 3550);
DISPLAY INVISIBLE (-3200 3550);
FORCEPROP 1 LAST BODY_TYPE PLUMBING
J 0
(-3200 3500);
DISPLAY 1.234043 (-3200 3500);
PAINT GREEN (-3200 3500);
DISPLAY INVISIBLE (-3200 3500);
FORCEPROP 1 LAST HDL_TAP TRUE
J 0
(-2875 3425);
DISPLAY 1.234043 (-2875 3425);
PAINT GREEN (-2875 3425);
DISPLAY INVISIBLE (-2875 3425);
FORCEPROP 1 LAST PATH I134
J 0
(-3200 3550);
DISPLAY 0.936170 (-3200 3550);
PAINT GREEN (-3200 3550);
DISPLAY INVISIBLE (-3200 3550);
FORCEADD OFFPAGE..1
(-3850 3200);
FORCEPROP 2 LAST $XR0 24 
J 0
(-4101 3200);
DISPLAY 0.638298 (-4101 3200);
PAINT MONO (-4101 3200);
FORCEPROP 2 LAST $XR1 46 
J 0
(-4191 3200);
DISPLAY 0.638298 (-4191 3200);
PAINT MONO (-4191 3200);
FORCEPROP 2 LAST CDS_LIB mstr_standard
J 0
(-3850 3200);
DISPLAY 0.787234 (-3850 3200);
PAINT MONO (-3850 3200);
DISPLAY INVISIBLE (-3850 3200);
FORCEPROP 1 LAST OFFPAGE TRUE
J 0
(-3525 3075);
DISPLAY 0.936170 (-3525 3075);
PAINT GREEN (-3525 3075);
DISPLAY INVISIBLE (-3525 3075);
FORCEPROP 1 LAST COMMENT_BODY TRUE
J 0
(-3725 3100);
DISPLAY 0.936170 (-3725 3100);
PAINT GREEN (-3725 3100);
DISPLAY INVISIBLE (-3725 3100);
FORCEPROP 2 LAST PATH I135
J 0
(-3800 3275);
DISPLAY 0.787234 (-3800 3275);
PAINT MONO (-3800 3275);
DISPLAY INVISIBLE (-3800 3275);
FORCEADD OFFPAGE..1
(-3850 3700);
FORCEPROP 2 LAST $XR0 24 
J 0
(-4101 3700);
DISPLAY 0.638298 (-4101 3700);
PAINT MONO (-4101 3700);
FORCEPROP 2 LAST $XR1 46 
J 0
(-4191 3700);
DISPLAY 0.638298 (-4191 3700);
PAINT MONO (-4191 3700);
FORCEPROP 2 LAST CDS_LIB mstr_standard
J 0
(-3850 3700);
DISPLAY 0.787234 (-3850 3700);
PAINT MONO (-3850 3700);
DISPLAY INVISIBLE (-3850 3700);
FORCEPROP 1 LAST OFFPAGE TRUE
J 0
(-3525 3575);
DISPLAY 0.936170 (-3525 3575);
PAINT GREEN (-3525 3575);
DISPLAY INVISIBLE (-3525 3575);
FORCEPROP 1 LAST COMMENT_BODY TRUE
J 0
(-3725 3600);
DISPLAY 0.936170 (-3725 3600);
PAINT GREEN (-3725 3600);
DISPLAY INVISIBLE (-3725 3600);
FORCEPROP 2 LAST PATH I136
J 0
(-3800 3775);
DISPLAY 0.787234 (-3800 3775);
PAINT MONO (-3800 3775);
DISPLAY INVISIBLE (-3800 3775);
FORCEADD OFFPAGE..1
(-3850 3600);
FORCEPROP 2 LAST $XR0 24 
J 0
(-4101 3600);
DISPLAY 0.638298 (-4101 3600);
PAINT MONO (-4101 3600);
FORCEPROP 2 LAST $XR1 46 
J 0
(-4191 3600);
DISPLAY 0.638298 (-4191 3600);
PAINT MONO (-4191 3600);
FORCEPROP 2 LAST CDS_LIB mstr_standard
J 0
(-3850 3600);
DISPLAY 0.787234 (-3850 3600);
PAINT MONO (-3850 3600);
DISPLAY INVISIBLE (-3850 3600);
FORCEPROP 1 LAST OFFPAGE TRUE
J 0
(-3525 3475);
DISPLAY 0.936170 (-3525 3475);
PAINT GREEN (-3525 3475);
DISPLAY INVISIBLE (-3525 3475);
FORCEPROP 1 LAST COMMENT_BODY TRUE
J 0
(-3725 3500);
DISPLAY 0.936170 (-3725 3500);
PAINT GREEN (-3725 3500);
DISPLAY INVISIBLE (-3725 3500);
FORCEPROP 2 LAST PATH I137
J 0
(-3800 3675);
DISPLAY 0.787234 (-3800 3675);
PAINT MONO (-3800 3675);
DISPLAY INVISIBLE (-3800 3675);
FORCEADD TAP..6
(-3200 2550);
FORCEPROP 3 LASTPIN (-3150 2550) SIG_NAME M_B_ECC<6>
J 0
(-3140 2560);
DISPLAY 0.659574 (-3140 2560);
PAINT MONO (-3140 2560);
DISPLAY INVISIBLE (-3140 2560);
FORCEPROP 1 LASTPIN (-3150 2550) BN 6
J 0
(-3200 2560);
DISPLAY 0.617021 (-3200 2560);
PAINT PINK (-3200 2560);
FORCEPROP 2 LAST CDS_LIB mstr_standard
J 0
(-3200 2550);
DISPLAY 0.787234 (-3200 2550);
PAINT MONO (-3200 2550);
DISPLAY INVISIBLE (-3200 2550);
FORCEPROP 1 LAST BODY_TYPE PLUMBING
J 0
(-3200 2500);
DISPLAY 1.234043 (-3200 2500);
PAINT GREEN (-3200 2500);
DISPLAY INVISIBLE (-3200 2500);
FORCEPROP 1 LAST HDL_TAP TRUE
J 0
(-2875 2425);
DISPLAY 1.234043 (-2875 2425);
PAINT GREEN (-2875 2425);
DISPLAY INVISIBLE (-2875 2425);
FORCEPROP 1 LAST PATH I138
J 0
(-3200 2550);
DISPLAY 0.936170 (-3200 2550);
PAINT GREEN (-3200 2550);
DISPLAY INVISIBLE (-3200 2550);
FORCEADD TAP..6
(-3200 2500);
FORCEPROP 3 LASTPIN (-3150 2500) SIG_NAME M_B_ECC<7>
J 0
(-3140 2510);
DISPLAY 0.659574 (-3140 2510);
PAINT MONO (-3140 2510);
DISPLAY INVISIBLE (-3140 2510);
FORCEPROP 1 LASTPIN (-3150 2500) BN 7
J 0
(-3200 2510);
DISPLAY 0.617021 (-3200 2510);
PAINT PINK (-3200 2510);
FORCEPROP 2 LAST CDS_LIB mstr_standard
J 0
(-3200 2500);
DISPLAY 0.787234 (-3200 2500);
PAINT MONO (-3200 2500);
DISPLAY INVISIBLE (-3200 2500);
FORCEPROP 1 LAST BODY_TYPE PLUMBING
J 0
(-3200 2450);
DISPLAY 1.234043 (-3200 2450);
PAINT GREEN (-3200 2450);
DISPLAY INVISIBLE (-3200 2450);
FORCEPROP 1 LAST HDL_TAP TRUE
J 0
(-2875 2375);
DISPLAY 1.234043 (-2875 2375);
PAINT GREEN (-2875 2375);
DISPLAY INVISIBLE (-2875 2375);
FORCEPROP 1 LAST PATH I139
J 0
(-3200 2500);
DISPLAY 0.936170 (-3200 2500);
PAINT GREEN (-3200 2500);
DISPLAY INVISIBLE (-3200 2500);
FORCEADD TAP..6
R 2
(900 4600);
FORCEPROP 3 LASTPIN (850 4600) SIG_NAME M_B_DQS_DN<12>
J 0
(860 4610);
DISPLAY 0.659574 (860 4610);
PAINT MONO (860 4610);
DISPLAY INVISIBLE (860 4610);
FORCEPROP 1 LASTPIN (850 4600) BN 12
J 2
(900 4610);
DISPLAY 0.617021 (900 4610);
PAINT PINK (900 4610);
FORCEPROP 2 LAST CDS_LIB mstr_standard
J 0
(900 4600);
DISPLAY 0.787234 (900 4600);
PAINT MONO (900 4600);
DISPLAY INVISIBLE (900 4600);
FORCEPROP 1 LAST BODY_TYPE PLUMBING
J 2
(900 4550);
DISPLAY 1.234043 (900 4550);
PAINT GREEN (900 4550);
DISPLAY INVISIBLE (900 4550);
FORCEPROP 1 LAST HDL_TAP TRUE
J 2
(575 4475);
DISPLAY 1.234043 (575 4475);
PAINT GREEN (575 4475);
DISPLAY INVISIBLE (575 4475);
FORCEPROP 1 LAST PATH I14
J 2
(900 4600);
DISPLAY 0.936170 (900 4600);
PAINT GREEN (900 4600);
DISPLAY INVISIBLE (900 4600);
FORCEADD TAP..6
(-3200 2450);
FORCEPROP 3 LASTPIN (-3150 2450) SIG_NAME M_B_ECC<4>
J 0
(-3140 2460);
DISPLAY 0.659574 (-3140 2460);
PAINT MONO (-3140 2460);
DISPLAY INVISIBLE (-3140 2460);
FORCEPROP 1 LASTPIN (-3150 2450) BN 4
J 0
(-3200 2460);
DISPLAY 0.617021 (-3200 2460);
PAINT PINK (-3200 2460);
FORCEPROP 2 LAST CDS_LIB mstr_standard
J 0
(-3200 2450);
DISPLAY 0.787234 (-3200 2450);
PAINT MONO (-3200 2450);
DISPLAY INVISIBLE (-3200 2450);
FORCEPROP 1 LAST BODY_TYPE PLUMBING
J 0
(-3200 2400);
DISPLAY 1.234043 (-3200 2400);
PAINT GREEN (-3200 2400);
DISPLAY INVISIBLE (-3200 2400);
FORCEPROP 1 LAST HDL_TAP TRUE
J 0
(-2875 2325);
DISPLAY 1.234043 (-2875 2325);
PAINT GREEN (-2875 2325);
DISPLAY INVISIBLE (-2875 2325);
FORCEPROP 1 LAST PATH I140
J 0
(-3200 2450);
DISPLAY 0.936170 (-3200 2450);
PAINT GREEN (-3200 2450);
DISPLAY INVISIBLE (-3200 2450);
FORCEADD TAP..6
(-3200 2400);
FORCEPROP 3 LASTPIN (-3150 2400) SIG_NAME M_B_ECC<5>
J 0
(-3140 2410);
DISPLAY 0.659574 (-3140 2410);
PAINT MONO (-3140 2410);
DISPLAY INVISIBLE (-3140 2410);
FORCEPROP 1 LASTPIN (-3150 2400) BN 5
J 0
(-3200 2410);
DISPLAY 0.617021 (-3200 2410);
PAINT PINK (-3200 2410);
FORCEPROP 2 LAST CDS_LIB mstr_standard
J 0
(-3200 2400);
DISPLAY 0.787234 (-3200 2400);
PAINT MONO (-3200 2400);
DISPLAY INVISIBLE (-3200 2400);
FORCEPROP 1 LAST BODY_TYPE PLUMBING
J 0
(-3200 2350);
DISPLAY 1.234043 (-3200 2350);
PAINT GREEN (-3200 2350);
DISPLAY INVISIBLE (-3200 2350);
FORCEPROP 1 LAST HDL_TAP TRUE
J 0
(-2875 2275);
DISPLAY 1.234043 (-2875 2275);
PAINT GREEN (-2875 2275);
DISPLAY INVISIBLE (-2875 2275);
FORCEPROP 1 LAST PATH I141
J 0
(-3200 2400);
DISPLAY 0.936170 (-3200 2400);
PAINT GREEN (-3200 2400);
DISPLAY INVISIBLE (-3200 2400);
FORCEADD TAP..6
(-3200 2350);
FORCEPROP 3 LASTPIN (-3150 2350) SIG_NAME M_B_ECC<2>
J 0
(-3140 2360);
DISPLAY 0.659574 (-3140 2360);
PAINT MONO (-3140 2360);
DISPLAY INVISIBLE (-3140 2360);
FORCEPROP 1 LASTPIN (-3150 2350) BN 2
J 0
(-3200 2360);
DISPLAY 0.617021 (-3200 2360);
PAINT PINK (-3200 2360);
FORCEPROP 2 LAST CDS_LIB mstr_standard
J 0
(-3200 2350);
DISPLAY 0.787234 (-3200 2350);
PAINT MONO (-3200 2350);
DISPLAY INVISIBLE (-3200 2350);
FORCEPROP 1 LAST BODY_TYPE PLUMBING
J 0
(-3200 2300);
DISPLAY 1.234043 (-3200 2300);
PAINT GREEN (-3200 2300);
DISPLAY INVISIBLE (-3200 2300);
FORCEPROP 1 LAST HDL_TAP TRUE
J 0
(-2875 2225);
DISPLAY 1.234043 (-2875 2225);
PAINT GREEN (-2875 2225);
DISPLAY INVISIBLE (-2875 2225);
FORCEPROP 1 LAST PATH I142
J 0
(-3200 2350);
DISPLAY 0.936170 (-3200 2350);
PAINT GREEN (-3200 2350);
DISPLAY INVISIBLE (-3200 2350);
FORCEADD TAP..6
(-3200 2300);
FORCEPROP 3 LASTPIN (-3150 2300) SIG_NAME M_B_ECC<3>
J 0
(-3140 2310);
DISPLAY 0.659574 (-3140 2310);
PAINT MONO (-3140 2310);
DISPLAY INVISIBLE (-3140 2310);
FORCEPROP 1 LASTPIN (-3150 2300) BN 3
J 0
(-3200 2310);
DISPLAY 0.617021 (-3200 2310);
PAINT PINK (-3200 2310);
FORCEPROP 2 LAST CDS_LIB mstr_standard
J 0
(-3200 2300);
DISPLAY 0.787234 (-3200 2300);
PAINT MONO (-3200 2300);
DISPLAY INVISIBLE (-3200 2300);
FORCEPROP 1 LAST BODY_TYPE PLUMBING
J 0
(-3200 2250);
DISPLAY 1.234043 (-3200 2250);
PAINT GREEN (-3200 2250);
DISPLAY INVISIBLE (-3200 2250);
FORCEPROP 1 LAST HDL_TAP TRUE
J 0
(-2875 2175);
DISPLAY 1.234043 (-2875 2175);
PAINT GREEN (-2875 2175);
DISPLAY INVISIBLE (-2875 2175);
FORCEPROP 1 LAST PATH I143
J 0
(-3200 2300);
DISPLAY 0.936170 (-3200 2300);
PAINT GREEN (-3200 2300);
DISPLAY INVISIBLE (-3200 2300);
FORCEADD TAP..6
(-3200 2250);
FORCEPROP 3 LASTPIN (-3150 2250) SIG_NAME M_B_ECC<0>
J 0
(-3140 2260);
DISPLAY 0.659574 (-3140 2260);
PAINT MONO (-3140 2260);
DISPLAY INVISIBLE (-3140 2260);
FORCEPROP 1 LASTPIN (-3150 2250) BN 0
J 0
(-3200 2260);
DISPLAY 0.617021 (-3200 2260);
PAINT PINK (-3200 2260);
FORCEPROP 2 LAST CDS_LIB mstr_standard
J 0
(-3200 2250);
DISPLAY 0.787234 (-3200 2250);
PAINT MONO (-3200 2250);
DISPLAY INVISIBLE (-3200 2250);
FORCEPROP 1 LAST BODY_TYPE PLUMBING
J 0
(-3200 2200);
DISPLAY 1.234043 (-3200 2200);
PAINT GREEN (-3200 2200);
DISPLAY INVISIBLE (-3200 2200);
FORCEPROP 1 LAST HDL_TAP TRUE
J 0
(-2875 2125);
DISPLAY 1.234043 (-2875 2125);
PAINT GREEN (-2875 2125);
DISPLAY INVISIBLE (-2875 2125);
FORCEPROP 1 LAST PATH I144
J 0
(-3200 2250);
DISPLAY 0.936170 (-3200 2250);
PAINT GREEN (-3200 2250);
DISPLAY INVISIBLE (-3200 2250);
FORCEADD TAP..6
(-3200 2200);
FORCEPROP 3 LASTPIN (-3150 2200) SIG_NAME M_B_ECC<1>
J 0
(-3140 2210);
DISPLAY 0.659574 (-3140 2210);
PAINT MONO (-3140 2210);
DISPLAY INVISIBLE (-3140 2210);
FORCEPROP 1 LASTPIN (-3150 2200) BN 1
J 0
(-3200 2210);
DISPLAY 0.617021 (-3200 2210);
PAINT PINK (-3200 2210);
FORCEPROP 2 LAST CDS_LIB mstr_standard
J 0
(-3200 2200);
DISPLAY 0.787234 (-3200 2200);
PAINT MONO (-3200 2200);
DISPLAY INVISIBLE (-3200 2200);
FORCEPROP 1 LAST BODY_TYPE PLUMBING
J 0
(-3200 2150);
DISPLAY 1.234043 (-3200 2150);
PAINT GREEN (-3200 2150);
DISPLAY INVISIBLE (-3200 2150);
FORCEPROP 1 LAST HDL_TAP TRUE
J 0
(-2875 2075);
DISPLAY 1.234043 (-2875 2075);
PAINT GREEN (-2875 2075);
DISPLAY INVISIBLE (-2875 2075);
FORCEPROP 1 LAST PATH I145
J 0
(-3200 2200);
DISPLAY 0.936170 (-3200 2200);
PAINT GREEN (-3200 2200);
DISPLAY INVISIBLE (-3200 2200);
FORCEADD OFFPAGE..1
(-3850 2550);
FORCEPROP 2 LAST $XR0 24 
J 0
(-4101 2550);
DISPLAY 0.638298 (-4101 2550);
PAINT MONO (-4101 2550);
FORCEPROP 2 LAST $XR1 46 
J 0
(-4191 2550);
DISPLAY 0.638298 (-4191 2550);
PAINT MONO (-4191 2550);
FORCEPROP 2 LAST CDS_LIB mstr_standard
J 0
(-3850 2550);
DISPLAY 0.787234 (-3850 2550);
PAINT MONO (-3850 2550);
DISPLAY INVISIBLE (-3850 2550);
FORCEPROP 1 LAST OFFPAGE TRUE
J 0
(-3525 2425);
DISPLAY 0.936170 (-3525 2425);
PAINT GREEN (-3525 2425);
DISPLAY INVISIBLE (-3525 2425);
FORCEPROP 1 LAST COMMENT_BODY TRUE
J 0
(-3725 2450);
DISPLAY 0.936170 (-3725 2450);
PAINT GREEN (-3725 2450);
DISPLAY INVISIBLE (-3725 2450);
FORCEPROP 2 LAST PATH I146
J 0
(-3800 2625);
DISPLAY 0.787234 (-3800 2625);
PAINT MONO (-3800 2625);
DISPLAY INVISIBLE (-3800 2625);
FORCEADD OFFPAGE..1
(-3850 2500);
FORCEPROP 2 LAST $XR0 21 
J 0
(-4101 2500);
DISPLAY 0.638298 (-4101 2500);
PAINT MONO (-4101 2500);
FORCEPROP 2 LAST $XR1 43 
J 0
(-4191 2500);
DISPLAY 0.638298 (-4191 2500);
PAINT MONO (-4191 2500);
FORCEPROP 2 LAST $XR2 44 
J 0
(-4281 2500);
DISPLAY 0.638298 (-4281 2500);
PAINT MONO (-4281 2500);
FORCEPROP 2 LAST $XR3 46 
J 0
(-4371 2500);
DISPLAY 0.638298 (-4371 2500);
PAINT MONO (-4371 2500);
FORCEPROP 2 LAST $XR4 47 
J 0
(-4461 2500);
DISPLAY 0.638298 (-4461 2500);
PAINT MONO (-4461 2500);
FORCEPROP 2 LAST $XR5 48 
J 0
(-4551 2500);
DISPLAY 0.638298 (-4551 2500);
PAINT MONO (-4551 2500);
FORCEPROP 2 LAST CDS_LIB mstr_standard
J 0
(-3850 2500);
DISPLAY 0.787234 (-3850 2500);
PAINT MONO (-3850 2500);
DISPLAY INVISIBLE (-3850 2500);
FORCEPROP 1 LAST OFFPAGE TRUE
J 0
(-3525 2375);
DISPLAY 0.936170 (-3525 2375);
PAINT GREEN (-3525 2375);
DISPLAY INVISIBLE (-3525 2375);
FORCEPROP 1 LAST COMMENT_BODY TRUE
J 0
(-3725 2400);
DISPLAY 0.936170 (-3725 2400);
PAINT GREEN (-3725 2400);
DISPLAY INVISIBLE (-3725 2400);
FORCEPROP 2 LAST PATH I147
J 0
(-3800 2575);
DISPLAY 0.787234 (-3800 2575);
PAINT MONO (-3800 2575);
DISPLAY INVISIBLE (-3800 2575);
FORCEADD OFFPAGE..5
(-4025 1950);
FORCEPROP 2 LAST $XR0 46 
J 0
(-4249 1950);
DISPLAY 0.638298 (-4249 1950);
PAINT MONO (-4249 1950);
FORCEPROP 2 LAST $XR1 24 
J 0
(-4339 1950);
DISPLAY 0.638298 (-4339 1950);
PAINT MONO (-4339 1950);
FORCEPROP 2 LAST CDS_LIB mstr_standard
J 0
(-4025 1950);
DISPLAY 0.787234 (-4025 1950);
PAINT MONO (-4025 1950);
DISPLAY INVISIBLE (-4025 1950);
FORCEPROP 1 LAST OFFPAGE TRUE
J 0
(-3700 1825);
DISPLAY 1.404255 (-3700 1825);
PAINT GREEN (-3700 1825);
DISPLAY INVISIBLE (-3700 1825);
FORCEPROP 1 LAST COMMENT_BODY TRUE
J 0
(-3925 1875);
DISPLAY 1.404255 (-3925 1875);
PAINT GREEN (-3925 1875);
DISPLAY INVISIBLE (-3925 1875);
FORCEPROP 2 LAST PATH I148
J 0
(-3975 2025);
DISPLAY 0.787234 (-3975 2025);
PAINT MONO (-3975 2025);
DISPLAY INVISIBLE (-3975 2025);
FORCEADD OFFPAGE..1
(-4000 1900);
FORCEPROP 2 LAST $XR0 24 
J 0
(-4251 1900);
DISPLAY 0.638298 (-4251 1900);
PAINT MONO (-4251 1900);
FORCEPROP 2 LAST $XR1 46 
J 0
(-4341 1900);
DISPLAY 0.638298 (-4341 1900);
PAINT MONO (-4341 1900);
FORCEPROP 2 LAST CDS_LIB mstr_standard
J 0
(-4000 1900);
DISPLAY 0.787234 (-4000 1900);
PAINT MONO (-4000 1900);
DISPLAY INVISIBLE (-4000 1900);
FORCEPROP 1 LAST OFFPAGE TRUE
J 0
(-3675 1775);
DISPLAY 0.936170 (-3675 1775);
PAINT GREEN (-3675 1775);
DISPLAY INVISIBLE (-3675 1775);
FORCEPROP 1 LAST COMMENT_BODY TRUE
J 0
(-3875 1800);
DISPLAY 0.936170 (-3875 1800);
PAINT GREEN (-3875 1800);
DISPLAY INVISIBLE (-3875 1800);
FORCEPROP 2 LAST PATH I149
J 0
(-3950 1975);
DISPLAY 0.787234 (-3950 1975);
PAINT MONO (-3950 1975);
DISPLAY INVISIBLE (-3950 1975);
FORCEADD TAP..6
R 2
(900 4700);
FORCEPROP 3 LASTPIN (850 4700) SIG_NAME M_B_DQS_DN<13>
J 0
(860 4710);
DISPLAY 0.659574 (860 4710);
PAINT MONO (860 4710);
DISPLAY INVISIBLE (860 4710);
FORCEPROP 1 LASTPIN (850 4700) BN 13
J 2
(900 4710);
DISPLAY 0.617021 (900 4710);
PAINT PINK (900 4710);
FORCEPROP 2 LAST CDS_LIB mstr_standard
J 0
(900 4700);
DISPLAY 0.787234 (900 4700);
PAINT MONO (900 4700);
DISPLAY INVISIBLE (900 4700);
FORCEPROP 1 LAST BODY_TYPE PLUMBING
J 2
(900 4650);
DISPLAY 1.234043 (900 4650);
PAINT GREEN (900 4650);
DISPLAY INVISIBLE (900 4650);
FORCEPROP 1 LAST HDL_TAP TRUE
J 2
(575 4575);
DISPLAY 1.234043 (575 4575);
PAINT GREEN (575 4575);
DISPLAY INVISIBLE (575 4575);
FORCEPROP 1 LAST PATH I15
J 2
(900 4700);
DISPLAY 0.936170 (900 4700);
PAINT GREEN (900 4700);
DISPLAY INVISIBLE (900 4700);
FORCEADD OFFPAGE..6
(-3850 2600);
FORCEPROP 2 LAST $XR0 24 
J 0
(-4099 2600);
DISPLAY 0.638298 (-4099 2600);
PAINT MONO (-4099 2600);
FORCEPROP 2 LAST $XR1 46 
J 0
(-4189 2600);
DISPLAY 0.638298 (-4189 2600);
PAINT MONO (-4189 2600);
FORCEPROP 2 LAST CDS_LIB mstr_standard
J 0
(-3850 2600);
DISPLAY 0.787234 (-3850 2600);
PAINT MONO (-3850 2600);
DISPLAY INVISIBLE (-3850 2600);
FORCEPROP 1 LAST OFFPAGE TRUE
J 0
(-3525 2475);
DISPLAY 0.936170 (-3525 2475);
PAINT GREEN (-3525 2475);
DISPLAY INVISIBLE (-3525 2475);
FORCEPROP 1 LAST COMMENT_BODY TRUE
J 0
(-3750 2525);
DISPLAY 0.936170 (-3750 2525);
PAINT GREEN (-3750 2525);
DISPLAY INVISIBLE (-3750 2525);
FORCEPROP 2 LAST PATH I150
J 0
(-3800 2675);
DISPLAY 0.787234 (-3800 2675);
PAINT MONO (-3800 2675);
DISPLAY INVISIBLE (-3800 2675);
FORCEADD OFFPAGE..1
(-4750 1450);
FORCEPROP 2 LAST $XR0 98 
J 0
(-4971 1450);
DISPLAY 0.638298 (-4971 1450);
PAINT MONO (-4971 1450);
FORCEPROP 2 LAST $XR1 46 
J 0
(-5061 1450);
DISPLAY 0.638298 (-5061 1450);
PAINT MONO (-5061 1450);
FORCEPROP 2 LAST CDS_LIB mstr_standard
J 0
(-4750 1450);
DISPLAY 0.787234 (-4750 1450);
PAINT MONO (-4750 1450);
DISPLAY INVISIBLE (-4750 1450);
FORCEPROP 1 LAST OFFPAGE TRUE
J 0
(-4425 1325);
DISPLAY 0.936170 (-4425 1325);
PAINT GREEN (-4425 1325);
DISPLAY INVISIBLE (-4425 1325);
FORCEPROP 1 LAST COMMENT_BODY TRUE
J 0
(-4625 1350);
DISPLAY 0.936170 (-4625 1350);
PAINT GREEN (-4625 1350);
DISPLAY INVISIBLE (-4625 1350);
FORCEPROP 2 LAST PATH I151
J 0
(-4700 1525);
DISPLAY 0.787234 (-4700 1525);
PAINT MONO (-4700 1525);
DISPLAY INVISIBLE (-4700 1525);
FORCEADD TAP..6
(-3200 2700);
FORCEPROP 3 LASTPIN (-3150 2700) SIG_NAME M_B_ODT<1>
J 0
(-3140 2710);
DISPLAY 0.659574 (-3140 2710);
PAINT MONO (-3140 2710);
DISPLAY INVISIBLE (-3140 2710);
FORCEPROP 1 LASTPIN (-3150 2700) BN 1
J 0
(-3200 2710);
DISPLAY 0.617021 (-3200 2710);
PAINT PINK (-3200 2710);
FORCEPROP 2 LAST CDS_LIB mstr_standard
J 0
(-3200 2700);
DISPLAY 0.787234 (-3200 2700);
PAINT MONO (-3200 2700);
DISPLAY INVISIBLE (-3200 2700);
FORCEPROP 1 LAST BODY_TYPE PLUMBING
J 0
(-3200 2650);
DISPLAY 1.234043 (-3200 2650);
PAINT GREEN (-3200 2650);
DISPLAY INVISIBLE (-3200 2650);
FORCEPROP 1 LAST HDL_TAP TRUE
J 0
(-2875 2575);
DISPLAY 1.234043 (-2875 2575);
PAINT GREEN (-2875 2575);
DISPLAY INVISIBLE (-2875 2575);
FORCEPROP 1 LAST PATH I152
J 0
(-3200 2700);
DISPLAY 0.936170 (-3200 2700);
PAINT GREEN (-3200 2700);
DISPLAY INVISIBLE (-3200 2700);
FORCEADD TAP..6
(-3200 2650);
FORCEPROP 3 LASTPIN (-3150 2650) SIG_NAME M_B_ODT<0>
J 0
(-3140 2660);
DISPLAY 0.659574 (-3140 2660);
PAINT MONO (-3140 2660);
DISPLAY INVISIBLE (-3140 2660);
FORCEPROP 1 LASTPIN (-3150 2650) BN 0
J 0
(-3200 2660);
DISPLAY 0.617021 (-3200 2660);
PAINT PINK (-3200 2660);
FORCEPROP 2 LAST CDS_LIB mstr_standard
J 0
(-3200 2650);
DISPLAY 0.787234 (-3200 2650);
PAINT MONO (-3200 2650);
DISPLAY INVISIBLE (-3200 2650);
FORCEPROP 1 LAST BODY_TYPE PLUMBING
J 0
(-3200 2600);
DISPLAY 1.234043 (-3200 2600);
PAINT GREEN (-3200 2600);
DISPLAY INVISIBLE (-3200 2600);
FORCEPROP 1 LAST HDL_TAP TRUE
J 0
(-2875 2525);
DISPLAY 1.234043 (-2875 2525);
PAINT GREEN (-2875 2525);
DISPLAY INVISIBLE (-2875 2525);
FORCEPROP 1 LAST PATH I153
J 0
(-3200 2650);
DISPLAY 0.936170 (-3200 2650);
PAINT GREEN (-3200 2650);
DISPLAY INVISIBLE (-3200 2650);
FORCEADD OFFPAGE..1
(-3850 2800);
FORCEPROP 2 LAST $XR0 24 
J 0
(-4101 2800);
DISPLAY 0.638298 (-4101 2800);
PAINT MONO (-4101 2800);
FORCEPROP 2 LAST $XR1 46 
J 0
(-4191 2800);
DISPLAY 0.638298 (-4191 2800);
PAINT MONO (-4191 2800);
FORCEPROP 2 LAST CDS_LIB mstr_standard
J 0
(-3850 2800);
DISPLAY 0.787234 (-3850 2800);
PAINT MONO (-3850 2800);
DISPLAY INVISIBLE (-3850 2800);
FORCEPROP 1 LAST OFFPAGE TRUE
J 0
(-3525 2675);
DISPLAY 0.936170 (-3525 2675);
PAINT GREEN (-3525 2675);
DISPLAY INVISIBLE (-3525 2675);
FORCEPROP 1 LAST COMMENT_BODY TRUE
J 0
(-3725 2700);
DISPLAY 0.936170 (-3725 2700);
PAINT GREEN (-3725 2700);
DISPLAY INVISIBLE (-3725 2700);
FORCEPROP 2 LAST PATH I154
J 0
(-3800 2875);
DISPLAY 0.787234 (-3800 2875);
PAINT MONO (-3800 2875);
DISPLAY INVISIBLE (-3800 2875);
FORCEADD TAP..6
(-3200 2850);
FORCEPROP 3 LASTPIN (-3150 2850) SIG_NAME M_B_CKE<1>
J 0
(-3140 2860);
DISPLAY 0.659574 (-3140 2860);
PAINT MONO (-3140 2860);
DISPLAY INVISIBLE (-3140 2860);
FORCEPROP 1 LASTPIN (-3150 2850) BN 1
J 0
(-3200 2860);
DISPLAY 0.617021 (-3200 2860);
PAINT PINK (-3200 2860);
FORCEPROP 2 LAST CDS_LIB mstr_standard
J 0
(-3200 2850);
DISPLAY 0.787234 (-3200 2850);
PAINT MONO (-3200 2850);
DISPLAY INVISIBLE (-3200 2850);
FORCEPROP 1 LAST BODY_TYPE PLUMBING
J 0
(-3200 2800);
DISPLAY 1.234043 (-3200 2800);
PAINT GREEN (-3200 2800);
DISPLAY INVISIBLE (-3200 2800);
FORCEPROP 1 LAST HDL_TAP TRUE
J 0
(-2875 2725);
DISPLAY 1.234043 (-2875 2725);
PAINT GREEN (-2875 2725);
DISPLAY INVISIBLE (-2875 2725);
FORCEPROP 1 LAST PATH I155
J 0
(-3200 2850);
DISPLAY 0.936170 (-3200 2850);
PAINT GREEN (-3200 2850);
DISPLAY INVISIBLE (-3200 2850);
FORCEADD TAP..6
(-3200 2800);
FORCEPROP 3 LASTPIN (-3150 2800) SIG_NAME M_B_CKE<0>
J 0
(-3140 2810);
DISPLAY 0.659574 (-3140 2810);
PAINT MONO (-3140 2810);
DISPLAY INVISIBLE (-3140 2810);
FORCEPROP 1 LASTPIN (-3150 2800) BN 0
J 0
(-3200 2810);
DISPLAY 0.617021 (-3200 2810);
PAINT PINK (-3200 2810);
FORCEPROP 2 LAST CDS_LIB mstr_standard
J 0
(-3200 2800);
DISPLAY 0.787234 (-3200 2800);
PAINT MONO (-3200 2800);
DISPLAY INVISIBLE (-3200 2800);
FORCEPROP 1 LAST BODY_TYPE PLUMBING
J 0
(-3200 2750);
DISPLAY 1.234043 (-3200 2750);
PAINT GREEN (-3200 2750);
DISPLAY INVISIBLE (-3200 2750);
FORCEPROP 1 LAST HDL_TAP TRUE
J 0
(-2875 2675);
DISPLAY 1.234043 (-2875 2675);
PAINT GREEN (-2875 2675);
DISPLAY INVISIBLE (-2875 2675);
FORCEPROP 1 LAST PATH I156
J 0
(-3200 2800);
DISPLAY 0.936170 (-3200 2800);
PAINT GREEN (-3200 2800);
DISPLAY INVISIBLE (-3200 2800);
FORCEADD OFFPAGE..1
(-3850 2950);
FORCEPROP 2 LAST $XR0 24 
J 0
(-4101 2950);
DISPLAY 0.638298 (-4101 2950);
PAINT MONO (-4101 2950);
FORCEPROP 2 LAST $XR1 46 
J 0
(-4191 2950);
DISPLAY 0.638298 (-4191 2950);
PAINT MONO (-4191 2950);
FORCEPROP 2 LAST CDS_LIB mstr_standard
J 0
(-3850 2950);
DISPLAY 0.787234 (-3850 2950);
PAINT MONO (-3850 2950);
DISPLAY INVISIBLE (-3850 2950);
FORCEPROP 1 LAST OFFPAGE TRUE
J 0
(-3525 2825);
DISPLAY 0.936170 (-3525 2825);
PAINT GREEN (-3525 2825);
DISPLAY INVISIBLE (-3525 2825);
FORCEPROP 1 LAST COMMENT_BODY TRUE
J 0
(-3725 2850);
DISPLAY 0.936170 (-3725 2850);
PAINT GREEN (-3725 2850);
DISPLAY INVISIBLE (-3725 2850);
FORCEPROP 2 LAST PATH I157
J 0
(-3800 3025);
DISPLAY 0.787234 (-3800 3025);
PAINT MONO (-3800 3025);
DISPLAY INVISIBLE (-3800 3025);
FORCEADD TAP..6
(-3200 3100);
FORCEPROP 3 LASTPIN (-3150 3100) SIG_NAME M_B_CS_N<3>
J 0
(-3140 3110);
DISPLAY 0.659574 (-3140 3110);
PAINT MONO (-3140 3110);
DISPLAY INVISIBLE (-3140 3110);
FORCEPROP 1 LASTPIN (-3150 3100) BN 3
J 0
(-3200 3110);
DISPLAY 0.617021 (-3200 3110);
PAINT PINK (-3200 3110);
FORCEPROP 2 LAST CDS_LIB mstr_standard
J 0
(-3200 3100);
DISPLAY 0.787234 (-3200 3100);
PAINT MONO (-3200 3100);
DISPLAY INVISIBLE (-3200 3100);
FORCEPROP 1 LAST BODY_TYPE PLUMBING
J 0
(-3200 3050);
DISPLAY 1.234043 (-3200 3050);
PAINT GREEN (-3200 3050);
DISPLAY INVISIBLE (-3200 3050);
FORCEPROP 1 LAST HDL_TAP TRUE
J 0
(-2875 2975);
DISPLAY 1.234043 (-2875 2975);
PAINT GREEN (-2875 2975);
DISPLAY INVISIBLE (-2875 2975);
FORCEPROP 1 LAST PATH I158
J 0
(-3200 3100);
DISPLAY 0.936170 (-3200 3100);
PAINT GREEN (-3200 3100);
DISPLAY INVISIBLE (-3200 3100);
FORCEADD OFFPAGE..1
(-3850 3150);
FORCEPROP 2 LAST $XR0 24 
J 0
(-4101 3150);
DISPLAY 0.638298 (-4101 3150);
PAINT MONO (-4101 3150);
FORCEPROP 2 LAST $XR1 46 
J 0
(-4191 3150);
DISPLAY 0.638298 (-4191 3150);
PAINT MONO (-4191 3150);
FORCEPROP 2 LAST CDS_LIB mstr_standard
J 0
(-3850 3150);
DISPLAY 0.787234 (-3850 3150);
PAINT MONO (-3850 3150);
DISPLAY INVISIBLE (-3850 3150);
FORCEPROP 1 LAST OFFPAGE TRUE
J 0
(-3525 3025);
DISPLAY 0.936170 (-3525 3025);
PAINT GREEN (-3525 3025);
DISPLAY INVISIBLE (-3525 3025);
FORCEPROP 1 LAST COMMENT_BODY TRUE
J 0
(-3725 3050);
DISPLAY 0.936170 (-3725 3050);
PAINT GREEN (-3725 3050);
DISPLAY INVISIBLE (-3725 3050);
FORCEPROP 2 LAST PATH I159
J 0
(-3800 3225);
DISPLAY 0.787234 (-3800 3225);
PAINT MONO (-3800 3225);
DISPLAY INVISIBLE (-3800 3225);
FORCEADD TAP..6
R 2
(700 4750);
FORCEPROP 3 LASTPIN (650 4750) SIG_NAME M_B_DQS_DP<13>
J 0
(660 4760);
DISPLAY 0.659574 (660 4760);
PAINT MONO (660 4760);
DISPLAY INVISIBLE (660 4760);
FORCEPROP 1 LASTPIN (650 4750) BN 13
J 2
(700 4760);
DISPLAY 0.617021 (700 4760);
PAINT PINK (700 4760);
FORCEPROP 2 LAST CDS_LIB mstr_standard
J 0
(700 4750);
DISPLAY 0.787234 (700 4750);
PAINT MONO (700 4750);
DISPLAY INVISIBLE (700 4750);
FORCEPROP 1 LAST BODY_TYPE PLUMBING
J 2
(700 4700);
DISPLAY 1.234043 (700 4700);
PAINT GREEN (700 4700);
DISPLAY INVISIBLE (700 4700);
FORCEPROP 1 LAST HDL_TAP TRUE
J 2
(375 4625);
DISPLAY 1.234043 (375 4625);
PAINT GREEN (375 4625);
DISPLAY INVISIBLE (375 4625);
FORCEPROP 1 LAST PATH I16
J 2
(700 4750);
DISPLAY 0.936170 (700 4750);
PAINT GREEN (700 4750);
DISPLAY INVISIBLE (700 4750);
FORCEADD TAP..6
(-3200 3050);
FORCEPROP 3 LASTPIN (-3150 3050) SIG_NAME M_B_CS_N<2>
J 0
(-3140 3060);
DISPLAY 0.659574 (-3140 3060);
PAINT MONO (-3140 3060);
DISPLAY INVISIBLE (-3140 3060);
FORCEPROP 1 LASTPIN (-3150 3050) BN 2
J 0
(-3200 3060);
DISPLAY 0.617021 (-3200 3060);
PAINT PINK (-3200 3060);
FORCEPROP 2 LAST CDS_LIB mstr_standard
J 0
(-3200 3050);
DISPLAY 0.787234 (-3200 3050);
PAINT MONO (-3200 3050);
DISPLAY INVISIBLE (-3200 3050);
FORCEPROP 1 LAST BODY_TYPE PLUMBING
J 0
(-3200 3000);
DISPLAY 1.234043 (-3200 3000);
PAINT GREEN (-3200 3000);
DISPLAY INVISIBLE (-3200 3000);
FORCEPROP 1 LAST HDL_TAP TRUE
J 0
(-2875 2925);
DISPLAY 1.234043 (-2875 2925);
PAINT GREEN (-2875 2925);
DISPLAY INVISIBLE (-2875 2925);
FORCEPROP 1 LAST PATH I160
J 0
(-3200 3050);
DISPLAY 0.936170 (-3200 3050);
PAINT GREEN (-3200 3050);
DISPLAY INVISIBLE (-3200 3050);
FORCEADD TAP..6
(-3200 3000);
FORCEPROP 3 LASTPIN (-3150 3000) SIG_NAME M_B_CS_N<1>
J 0
(-3140 3010);
DISPLAY 0.659574 (-3140 3010);
PAINT MONO (-3140 3010);
DISPLAY INVISIBLE (-3140 3010);
FORCEPROP 1 LASTPIN (-3150 3000) BN 1
J 0
(-3200 3010);
DISPLAY 0.617021 (-3200 3010);
PAINT PINK (-3200 3010);
FORCEPROP 2 LAST CDS_LIB mstr_standard
J 0
(-3200 3000);
DISPLAY 0.787234 (-3200 3000);
PAINT MONO (-3200 3000);
DISPLAY INVISIBLE (-3200 3000);
FORCEPROP 1 LAST BODY_TYPE PLUMBING
J 0
(-3200 2950);
DISPLAY 1.234043 (-3200 2950);
PAINT GREEN (-3200 2950);
DISPLAY INVISIBLE (-3200 2950);
FORCEPROP 1 LAST HDL_TAP TRUE
J 0
(-2875 2875);
DISPLAY 1.234043 (-2875 2875);
PAINT GREEN (-2875 2875);
DISPLAY INVISIBLE (-2875 2875);
FORCEPROP 1 LAST PATH I161
J 0
(-3200 3000);
DISPLAY 0.936170 (-3200 3000);
PAINT GREEN (-3200 3000);
DISPLAY INVISIBLE (-3200 3000);
FORCEADD TAP..6
(-3200 2950);
FORCEPROP 3 LASTPIN (-3150 2950) SIG_NAME M_B_CS_N<0>
J 0
(-3140 2960);
DISPLAY 0.659574 (-3140 2960);
PAINT MONO (-3140 2960);
DISPLAY INVISIBLE (-3140 2960);
FORCEPROP 1 LASTPIN (-3150 2950) BN 0
J 0
(-3200 2960);
DISPLAY 0.617021 (-3200 2960);
PAINT PINK (-3200 2960);
FORCEPROP 2 LAST CDS_LIB mstr_standard
J 0
(-3200 2950);
DISPLAY 0.787234 (-3200 2950);
PAINT MONO (-3200 2950);
DISPLAY INVISIBLE (-3200 2950);
FORCEPROP 1 LAST BODY_TYPE PLUMBING
J 0
(-3200 2900);
DISPLAY 1.234043 (-3200 2900);
PAINT GREEN (-3200 2900);
DISPLAY INVISIBLE (-3200 2900);
FORCEPROP 1 LAST HDL_TAP TRUE
J 0
(-2875 2825);
DISPLAY 1.234043 (-2875 2825);
PAINT GREEN (-2875 2825);
DISPLAY INVISIBLE (-2875 2825);
FORCEPROP 1 LAST PATH I162
J 0
(-3200 2950);
DISPLAY 0.936170 (-3200 2950);
PAINT GREEN (-3200 2950);
DISPLAY INVISIBLE (-3200 2950);
FORCEADD TAP..6
(-3400 3350);
FORCEPROP 3 LASTPIN (-3350 3350) SIG_NAME M_B_CLK_DN<1>
J 0
(-3340 3360);
DISPLAY 0.659574 (-3340 3360);
PAINT MONO (-3340 3360);
DISPLAY INVISIBLE (-3340 3360);
FORCEPROP 1 LASTPIN (-3350 3350) BN 1
J 0
(-3400 3360);
DISPLAY 0.617021 (-3400 3360);
PAINT PINK (-3400 3360);
FORCEPROP 2 LAST CDS_LIB mstr_standard
J 0
(-3400 3350);
DISPLAY 0.787234 (-3400 3350);
PAINT MONO (-3400 3350);
DISPLAY INVISIBLE (-3400 3350);
FORCEPROP 1 LAST BODY_TYPE PLUMBING
J 0
(-3400 3300);
DISPLAY 1.234043 (-3400 3300);
PAINT GREEN (-3400 3300);
DISPLAY INVISIBLE (-3400 3300);
FORCEPROP 1 LAST HDL_TAP TRUE
J 0
(-3075 3225);
DISPLAY 1.234043 (-3075 3225);
PAINT GREEN (-3075 3225);
DISPLAY INVISIBLE (-3075 3225);
FORCEPROP 1 LAST PATH I163
J 0
(-3400 3350);
DISPLAY 0.936170 (-3400 3350);
PAINT GREEN (-3400 3350);
DISPLAY INVISIBLE (-3400 3350);
FORCEADD TAP..6
(-3400 3250);
FORCEPROP 3 LASTPIN (-3350 3250) SIG_NAME M_B_CLK_DN<0>
J 0
(-3340 3260);
DISPLAY 0.659574 (-3340 3260);
PAINT MONO (-3340 3260);
DISPLAY INVISIBLE (-3340 3260);
FORCEPROP 1 LASTPIN (-3350 3250) BN 0
J 0
(-3400 3260);
DISPLAY 0.617021 (-3400 3260);
PAINT PINK (-3400 3260);
FORCEPROP 2 LAST CDS_LIB mstr_standard
J 0
(-3400 3250);
DISPLAY 0.787234 (-3400 3250);
PAINT MONO (-3400 3250);
DISPLAY INVISIBLE (-3400 3250);
FORCEPROP 1 LAST BODY_TYPE PLUMBING
J 0
(-3400 3200);
DISPLAY 1.234043 (-3400 3200);
PAINT GREEN (-3400 3200);
DISPLAY INVISIBLE (-3400 3200);
FORCEPROP 1 LAST HDL_TAP TRUE
J 0
(-3075 3125);
DISPLAY 1.234043 (-3075 3125);
PAINT GREEN (-3075 3125);
DISPLAY INVISIBLE (-3075 3125);
FORCEPROP 1 LAST PATH I164
J 0
(-3400 3250);
DISPLAY 0.936170 (-3400 3250);
PAINT GREEN (-3400 3250);
DISPLAY INVISIBLE (-3400 3250);
FORCEADD TAP..6
(-3200 3300);
FORCEPROP 3 LASTPIN (-3150 3300) SIG_NAME M_B_CLK_DP<0>
J 0
(-3140 3310);
DISPLAY 0.659574 (-3140 3310);
PAINT MONO (-3140 3310);
DISPLAY INVISIBLE (-3140 3310);
FORCEPROP 1 LASTPIN (-3150 3300) BN 0
J 0
(-3200 3310);
DISPLAY 0.617021 (-3200 3310);
PAINT PINK (-3200 3310);
FORCEPROP 2 LAST CDS_LIB mstr_standard
J 0
(-3200 3300);
DISPLAY 0.787234 (-3200 3300);
PAINT MONO (-3200 3300);
DISPLAY INVISIBLE (-3200 3300);
FORCEPROP 1 LAST BODY_TYPE PLUMBING
J 0
(-3200 3250);
DISPLAY 1.234043 (-3200 3250);
PAINT GREEN (-3200 3250);
DISPLAY INVISIBLE (-3200 3250);
FORCEPROP 1 LAST HDL_TAP TRUE
J 0
(-2875 3175);
DISPLAY 1.234043 (-2875 3175);
PAINT GREEN (-2875 3175);
DISPLAY INVISIBLE (-2875 3175);
FORCEPROP 1 LAST PATH I165
J 0
(-3200 3300);
DISPLAY 0.936170 (-3200 3300);
PAINT GREEN (-3200 3300);
DISPLAY INVISIBLE (-3200 3300);
FORCEADD TAP..6
(-3200 3400);
FORCEPROP 3 LASTPIN (-3150 3400) SIG_NAME M_B_CLK_DP<1>
J 0
(-3140 3410);
DISPLAY 0.659574 (-3140 3410);
PAINT MONO (-3140 3410);
DISPLAY INVISIBLE (-3140 3410);
FORCEPROP 1 LASTPIN (-3150 3400) BN 1
J 0
(-3200 3410);
DISPLAY 0.617021 (-3200 3410);
PAINT PINK (-3200 3410);
FORCEPROP 2 LAST CDS_LIB mstr_standard
J 0
(-3200 3400);
DISPLAY 0.787234 (-3200 3400);
PAINT MONO (-3200 3400);
DISPLAY INVISIBLE (-3200 3400);
FORCEPROP 1 LAST BODY_TYPE PLUMBING
J 0
(-3200 3350);
DISPLAY 1.234043 (-3200 3350);
PAINT GREEN (-3200 3350);
DISPLAY INVISIBLE (-3200 3350);
FORCEPROP 1 LAST HDL_TAP TRUE
J 0
(-2875 3275);
DISPLAY 1.234043 (-2875 3275);
PAINT GREEN (-2875 3275);
DISPLAY INVISIBLE (-2875 3275);
FORCEPROP 1 LAST PATH I166
J 0
(-3200 3400);
DISPLAY 0.936170 (-3200 3400);
PAINT GREEN (-3200 3400);
DISPLAY INVISIBLE (-3200 3400);
FORCEADD OFFPAGE..1
(-4000 3450);
FORCEPROP 2 LAST $XR0 24 
J 0
(-4251 3450);
DISPLAY 0.638298 (-4251 3450);
PAINT MONO (-4251 3450);
FORCEPROP 2 LAST $XR1 46 
J 0
(-4341 3450);
DISPLAY 0.638298 (-4341 3450);
PAINT MONO (-4341 3450);
FORCEPROP 2 LAST CDS_LIB mstr_standard
J 0
(-4000 3450);
DISPLAY 0.787234 (-4000 3450);
PAINT MONO (-4000 3450);
DISPLAY INVISIBLE (-4000 3450);
FORCEPROP 1 LAST OFFPAGE TRUE
J 0
(-3675 3325);
DISPLAY 0.936170 (-3675 3325);
PAINT GREEN (-3675 3325);
DISPLAY INVISIBLE (-3675 3325);
FORCEPROP 1 LAST COMMENT_BODY TRUE
J 0
(-3875 3350);
DISPLAY 0.936170 (-3875 3350);
PAINT GREEN (-3875 3350);
DISPLAY INVISIBLE (-3875 3350);
FORCEPROP 2 LAST PATH I167
J 0
(-3950 3525);
DISPLAY 0.787234 (-3950 3525);
PAINT MONO (-3950 3525);
DISPLAY INVISIBLE (-3950 3525);
FORCEADD OFFPAGE..1
(-4000 3500);
FORCEPROP 2 LAST $XR0 24 
J 0
(-4251 3500);
DISPLAY 0.638298 (-4251 3500);
PAINT MONO (-4251 3500);
FORCEPROP 2 LAST $XR1 46 
J 0
(-4341 3500);
DISPLAY 0.638298 (-4341 3500);
PAINT MONO (-4341 3500);
FORCEPROP 2 LAST CDS_LIB mstr_standard
J 0
(-4000 3500);
DISPLAY 0.787234 (-4000 3500);
PAINT MONO (-4000 3500);
DISPLAY INVISIBLE (-4000 3500);
FORCEPROP 1 LAST OFFPAGE TRUE
J 0
(-3675 3375);
DISPLAY 0.936170 (-3675 3375);
PAINT GREEN (-3675 3375);
DISPLAY INVISIBLE (-3675 3375);
FORCEPROP 1 LAST COMMENT_BODY TRUE
J 0
(-3875 3400);
DISPLAY 0.936170 (-3875 3400);
PAINT GREEN (-3875 3400);
DISPLAY INVISIBLE (-3875 3400);
FORCEPROP 2 LAST PATH I168
J 0
(-3950 3575);
DISPLAY 0.787234 (-3950 3575);
PAINT MONO (-3950 3575);
DISPLAY INVISIBLE (-3950 3575);
FORCEADD SCONN288_H44441004..4
(50 2000);
FORCEPROP 1 LAST LOCATION J4G2
J 0
(-400 3100);
DISPLAY 0.617021 (-400 3100);
PAINT AQUA (-400 3100);
FORCEPROP 1 LAST PART_NUMBER H44441-004
J 0
(-400 950);
DISPLAY 0.617021 (-400 950);
PAINT BLUE (-400 950);
FORCEPROP 1 LAST MATERIAL SCONN
J 0
(-400 3050);
DISPLAY 0.617021 (-400 3050);
PAINT SKYBLUE (-400 3050);
FORCEPROP 2 LASTPIN (-450 2550) $PN 77
J 2
(-460 2560);
DISPLAY 0.617021 (-460 2560);
PAINT ORANGE (-460 2560);
FORCEPROP 2 LASTPIN (-450 2500) $PN 221
J 2
(-460 2510);
DISPLAY 0.617021 (-460 2510);
PAINT ORANGE (-460 2510);
FORCEPROP 2 LASTPIN (-450 2850) $PN 142
J 2
(-460 2860);
DISPLAY 0.617021 (-460 2860);
PAINT ORANGE (-460 2860);
FORCEPROP 2 LASTPIN (-450 2800) $PN 143
J 2
(-460 2810);
DISPLAY 0.617021 (-460 2810);
PAINT ORANGE (-460 2810);
FORCEPROP 2 LASTPIN (-450 2750) $PN 288
J 2
(-460 2760);
DISPLAY 0.617021 (-460 2760);
PAINT ORANGE (-460 2760);
FORCEPROP 2 LASTPIN (-450 2700) $PN 286
J 2
(-460 2710);
DISPLAY 0.617021 (-460 2710);
PAINT ORANGE (-460 2710);
FORCEPROP 2 LASTPIN (-450 2650) $PN 287
J 2
(-460 2660);
DISPLAY 0.617021 (-460 2660);
PAINT ORANGE (-460 2660);
FORCEPROP 2 LASTPIN (-450 2400) $PN 59
J 2
(-460 2410);
DISPLAY 0.617021 (-460 2410);
PAINT ORANGE (-460 2410);
FORCEPROP 2 LASTPIN (-450 2350) $PN 61
J 2
(-460 2360);
DISPLAY 0.617021 (-460 2360);
PAINT ORANGE (-460 2360);
FORCEPROP 2 LASTPIN (-450 2300) $PN 64
J 2
(-460 2310);
DISPLAY 0.617021 (-460 2310);
PAINT ORANGE (-460 2310);
FORCEPROP 2 LASTPIN (-450 2250) $PN 67
J 2
(-460 2260);
DISPLAY 0.617021 (-460 2260);
PAINT ORANGE (-460 2260);
FORCEPROP 2 LASTPIN (-450 2200) $PN 70
J 2
(-460 2210);
DISPLAY 0.617021 (-460 2210);
PAINT ORANGE (-460 2210);
FORCEPROP 2 LASTPIN (-450 2150) $PN 73
J 2
(-460 2160);
DISPLAY 0.617021 (-460 2160);
PAINT ORANGE (-460 2160);
FORCEPROP 2 LASTPIN (-450 2100) $PN 76
J 2
(-460 2110);
DISPLAY 0.617021 (-460 2110);
PAINT ORANGE (-460 2110);
FORCEPROP 2 LASTPIN (-450 2050) $PN 80
J 2
(-460 2060);
DISPLAY 0.617021 (-460 2060);
PAINT ORANGE (-460 2060);
FORCEPROP 2 LASTPIN (-450 2000) $PN 83
J 2
(-460 2010);
DISPLAY 0.617021 (-460 2010);
PAINT ORANGE (-460 2010);
FORCEPROP 2 LASTPIN (-450 1950) $PN 85
J 2
(-460 1960);
DISPLAY 0.617021 (-460 1960);
PAINT ORANGE (-460 1960);
FORCEPROP 2 LASTPIN (-450 1900) $PN 88
J 2
(-460 1910);
DISPLAY 0.617021 (-460 1910);
PAINT ORANGE (-460 1910);
FORCEPROP 2 LASTPIN (-450 1850) $PN 90
J 2
(-460 1860);
DISPLAY 0.617021 (-460 1860);
PAINT ORANGE (-460 1860);
FORCEPROP 2 LASTPIN (-450 1800) $PN 92
J 2
(-460 1810);
DISPLAY 0.617021 (-460 1810);
PAINT ORANGE (-460 1810);
FORCEPROP 2 LASTPIN (-450 1750) $PN 204
J 2
(-460 1760);
DISPLAY 0.617021 (-460 1760);
PAINT ORANGE (-460 1760);
FORCEPROP 2 LASTPIN (-450 1700) $PN 206
J 2
(-460 1710);
DISPLAY 0.617021 (-460 1710);
PAINT ORANGE (-460 1710);
FORCEPROP 2 LASTPIN (-450 1650) $PN 209
J 2
(-460 1660);
DISPLAY 0.617021 (-460 1660);
PAINT ORANGE (-460 1660);
FORCEPROP 2 LASTPIN (-450 1600) $PN 212
J 2
(-460 1610);
DISPLAY 0.617021 (-460 1610);
PAINT ORANGE (-460 1610);
FORCEPROP 2 LASTPIN (-450 1550) $PN 215
J 2
(-460 1560);
DISPLAY 0.617021 (-460 1560);
PAINT ORANGE (-460 1560);
FORCEPROP 2 LASTPIN (-450 1500) $PN 217
J 2
(-460 1510);
DISPLAY 0.617021 (-460 1510);
PAINT ORANGE (-460 1510);
FORCEPROP 2 LASTPIN (-450 1450) $PN 220
J 2
(-460 1460);
DISPLAY 0.617021 (-460 1460);
PAINT ORANGE (-460 1460);
FORCEPROP 2 LASTPIN (-450 1400) $PN 223
J 2
(-460 1410);
DISPLAY 0.617021 (-460 1410);
PAINT ORANGE (-460 1410);
FORCEPROP 2 LASTPIN (-450 1350) $PN 226
J 2
(-460 1360);
DISPLAY 0.617021 (-460 1360);
PAINT ORANGE (-460 1360);
FORCEPROP 2 LASTPIN (-450 1300) $PN 229
J 2
(-460 1310);
DISPLAY 0.617021 (-460 1310);
PAINT ORANGE (-460 1310);
FORCEPROP 2 LASTPIN (-450 1250) $PN 231
J 2
(-460 1260);
DISPLAY 0.617021 (-460 1260);
PAINT ORANGE (-460 1260);
FORCEPROP 2 LASTPIN (-450 1200) $PN 233
J 2
(-460 1210);
DISPLAY 0.617021 (-460 1210);
PAINT ORANGE (-460 1210);
FORCEPROP 2 LASTPIN (-450 1150) $PN 236
J 2
(-460 1160);
DISPLAY 0.617021 (-460 1160);
PAINT ORANGE (-460 1160);
FORCEPROP 2 LASTPIN (550 2850) $PN 1
J 0
(560 2860);
DISPLAY 0.617021 (560 2860);
PAINT ORANGE (560 2860);
FORCEPROP 2 LASTPIN (550 2800) $PN 145
J 0
(560 2810);
DISPLAY 0.617021 (560 2810);
PAINT ORANGE (560 2810);
FORCEPROP 1 LAST PACK_TYPE PIP
J 0
(-400 3150);
PAINT SKYBLUE (-400 3150);
DISPLAY INVISIBLE (-400 3150);
FORCEPROP 2 LAST BOM_COST MEM
J 0
(50 2000);
PAINT ORANGE (50 2000);
DISPLAY INVISIBLE (50 2000);
FORCEPROP 2 LAST CDS_LIB mstr_sconn
J 0
(50 2000);
PAINT ORANGE (50 2000);
DISPLAY INVISIBLE (50 2000);
FORCEPROP 2 LAST SEC_TYPE PIP
J 0
(-400 3150);
DISPLAY 1.021277 (-400 3150);
PAINT ORANGE (-400 3150);
DISPLAY INVISIBLE (-400 3150);
FORCEPROP 2 LAST SEC 4
J 0
(-400 3150);
DISPLAY 0.680851 (-400 3150);
PAINT MONO (-400 3150);
DISPLAY INVISIBLE (-400 3150);
FORCEPROP 2 LAST CDS_LOCATION J4G2
J 0
(-400 3100);
DISPLAY 0.617021 (-400 3100);
PAINT AQUA (-400 3100);
DISPLAY INVISIBLE (-400 3100);
FORCEPROP 1 LAST PATH I169
J 0
(50 3050);
PAINT GREEN (50 3050);
DISPLAY INVISIBLE (50 3050);
FORCEPROP 2 LAST ROOM DDR4_CH_B
J 0
(50 2000);
PAINT ORANGE (50 2000);
DISPLAY INVISIBLE (50 2000);
FORCEADD TAP..6
R 2
(700 4650);
FORCEPROP 3 LASTPIN (650 4650) SIG_NAME M_B_DQS_DP<12>
J 0
(660 4660);
DISPLAY 0.659574 (660 4660);
PAINT MONO (660 4660);
DISPLAY INVISIBLE (660 4660);
FORCEPROP 1 LASTPIN (650 4650) BN 12
J 2
(700 4660);
DISPLAY 0.617021 (700 4660);
PAINT PINK (700 4660);
FORCEPROP 2 LAST CDS_LIB mstr_standard
J 0
(700 4650);
DISPLAY 0.787234 (700 4650);
PAINT MONO (700 4650);
DISPLAY INVISIBLE (700 4650);
FORCEPROP 1 LAST BODY_TYPE PLUMBING
J 2
(700 4600);
DISPLAY 1.234043 (700 4600);
PAINT GREEN (700 4600);
DISPLAY INVISIBLE (700 4600);
FORCEPROP 1 LAST HDL_TAP TRUE
J 2
(375 4525);
DISPLAY 1.234043 (375 4525);
PAINT GREEN (375 4525);
DISPLAY INVISIBLE (375 4525);
FORCEPROP 1 LAST PATH I17
J 2
(700 4650);
DISPLAY 0.936170 (700 4650);
PAINT GREEN (700 4650);
DISPLAY INVISIBLE (700 4650);
FORCEADD GND..1
R 2
(-5050 1600);
FORCEPROP 3 LASTPIN (-5050 1650) SIG_NAME GND\g
J 0
(-5040 1660);
DISPLAY 0.659574 (-5040 1660);
PAINT MONO (-5040 1660);
DISPLAY INVISIBLE (-5040 1660);
FORCEPROP 1 LAST VOLTAGE 0
J 0
(-5050 1600);
PAINT SKYBLUE (-5050 1600);
DISPLAY INVISIBLE (-5050 1600);
FORCEPROP 2 LAST BOM_COST MEM
J 0
(-5050 1605);
PAINT ORANGE (-5050 1605);
DISPLAY INVISIBLE (-5050 1605);
FORCEPROP 2 LAST CDS_LIB mstr_symbols
J 0
(-5050 1600);
DISPLAY 0.787234 (-5050 1600);
PAINT MONO (-5050 1600);
DISPLAY INVISIBLE (-5050 1600);
FORCEPROP 1 LAST SIZE 1B
J 2
(-5125 1550);
DISPLAY 1.170213 (-5125 1550);
PAINT GREEN (-5125 1550);
DISPLAY INVISIBLE (-5125 1550);
FORCEPROP 1 LAST BODY_TYPE PLUMBING
J 2
(-5005 1557);
DISPLAY 0.340426 (-5005 1557);
PAINT GREEN (-5005 1557);
DISPLAY INVISIBLE (-5005 1557);
FORCEPROP 1 LAST PATH I174
J 2
(-5125 1600);
DISPLAY 1.404255 (-5125 1600);
PAINT GREEN (-5125 1600);
DISPLAY INVISIBLE (-5125 1600);
FORCEPROP 2 LAST ROOM DDR4_CH_A
J 0
(-5050 1605);
PAINT ORANGE (-5050 1605);
DISPLAY INVISIBLE (-5050 1605);
FORCEPROP 1 LAST HDL_POWER GND
J 2
(-5050 1750);
DISPLAY 0.553191 (-5050 1750);
PAINT GREEN (-5050 1750);
DISPLAY INVISIBLE (-5050 1750);
FORCEADD OFFPAGE..6
(-3850 1600);
FORCEPROP 2 LAST $XR0 43 
J 0
(-4099 1600);
DISPLAY 0.638298 (-4099 1600);
PAINT MONO (-4099 1600);
FORCEPROP 2 LAST $XR1 44 
J 0
(-4189 1600);
DISPLAY 0.638298 (-4189 1600);
PAINT MONO (-4189 1600);
FORCEPROP 2 LAST $XR2 46 
J 0
(-4279 1600);
DISPLAY 0.638298 (-4279 1600);
PAINT MONO (-4279 1600);
FORCEPROP 2 LAST $XR3 47 
J 0
(-4369 1600);
DISPLAY 0.638298 (-4369 1600);
PAINT MONO (-4369 1600);
FORCEPROP 2 LAST $XR4 48 
J 0
(-4459 1600);
DISPLAY 0.638298 (-4459 1600);
PAINT MONO (-4459 1600);
FORCEPROP 2 LAST $XR5 99 
J 0
(-4549 1600);
DISPLAY 0.638298 (-4549 1600);
PAINT MONO (-4549 1600);
FORCEPROP 2 LASTPIN (-3800 1600) SIG_NAME SMB_DDR_ABC_VPP_SDA
J 0
(-3760 1610);
DISPLAY 0.617021 (-3760 1610);
PAINT ORANGE (-3760 1610);
FORCEPROP 2 LAST CDS_LIB mstr_standard
J 0
(-3850 1600);
DISPLAY 0.787234 (-3850 1600);
PAINT MONO (-3850 1600);
DISPLAY INVISIBLE (-3850 1600);
FORCEPROP 1 LAST OFFPAGE TRUE
J 0
(-3525 1475);
DISPLAY 0.936170 (-3525 1475);
PAINT GREEN (-3525 1475);
DISPLAY INVISIBLE (-3525 1475);
FORCEPROP 1 LAST COMMENT_BODY TRUE
J 0
(-3750 1525);
DISPLAY 0.936170 (-3750 1525);
PAINT GREEN (-3750 1525);
DISPLAY INVISIBLE (-3750 1525);
FORCEPROP 2 LAST PATH I175
J 0
(-4150 1650);
DISPLAY 0.787234 (-4150 1650);
PAINT ORANGE (-4150 1650);
DISPLAY INVISIBLE (-4150 1650);
FORCEADD OFFPAGE..1
(-3850 1550);
FORCEPROP 2 LAST $XR0 99 
J 0
(-4101 1550);
DISPLAY 0.638298 (-4101 1550);
PAINT MONO (-4101 1550);
FORCEPROP 2 LAST $XR1 43 
J 0
(-4191 1550);
DISPLAY 0.638298 (-4191 1550);
PAINT MONO (-4191 1550);
FORCEPROP 2 LAST $XR2 44 
J 0
(-4281 1550);
DISPLAY 0.638298 (-4281 1550);
PAINT MONO (-4281 1550);
FORCEPROP 2 LAST $XR3 46 
J 0
(-4371 1550);
DISPLAY 0.638298 (-4371 1550);
PAINT MONO (-4371 1550);
FORCEPROP 2 LAST $XR4 47 
J 0
(-4461 1550);
DISPLAY 0.638298 (-4461 1550);
PAINT MONO (-4461 1550);
FORCEPROP 2 LAST $XR5 48 
J 0
(-4551 1550);
DISPLAY 0.638298 (-4551 1550);
PAINT MONO (-4551 1550);
FORCEPROP 2 LAST CDS_LIB mstr_standard
J 0
(-3850 1550);
DISPLAY 0.787234 (-3850 1550);
PAINT MONO (-3850 1550);
DISPLAY INVISIBLE (-3850 1550);
FORCEPROP 1 LAST OFFPAGE TRUE
J 0
(-3525 1425);
DISPLAY 0.936170 (-3525 1425);
PAINT GREEN (-3525 1425);
DISPLAY INVISIBLE (-3525 1425);
FORCEPROP 1 LAST COMMENT_BODY TRUE
J 0
(-3725 1450);
DISPLAY 0.936170 (-3725 1450);
PAINT GREEN (-3725 1450);
DISPLAY INVISIBLE (-3725 1450);
FORCEPROP 2 LAST PATH I176
J 0
(-4125 1600);
DISPLAY 0.787234 (-4125 1600);
PAINT ORANGE (-4125 1600);
DISPLAY INVISIBLE (-4125 1600);
FORCEADD OFFPAGE..5
(-4175 2300);
FORCEPROP 2 LAST $XR0 43 
J 0
(-4429 2300);
DISPLAY 0.638298 (-4429 2300);
PAINT MONO (-4429 2300);
FORCEPROP 2 LAST $XR1 44 
J 0
(-4519 2300);
DISPLAY 0.638298 (-4519 2300);
PAINT MONO (-4519 2300);
FORCEPROP 2 LAST $XR2 46 
J 0
(-4609 2300);
DISPLAY 0.638298 (-4609 2300);
PAINT MONO (-4609 2300);
FORCEPROP 2 LAST $XR3 47 
J 0
(-4699 2300);
DISPLAY 0.638298 (-4699 2300);
PAINT MONO (-4699 2300);
FORCEPROP 2 LAST $XR4 48 
J 0
(-4789 2300);
DISPLAY 0.638298 (-4789 2300);
PAINT MONO (-4789 2300);
FORCEPROP 2 LAST $XR5 49 
J 0
(-4879 2300);
DISPLAY 0.638298 (-4879 2300);
PAINT MONO (-4879 2300);
FORCEPROP 2 LAST $XR6 50 
J 0
(-4969 2300);
DISPLAY 0.638298 (-4969 2300);
PAINT MONO (-4969 2300);
FORCEPROP 2 LAST $XR7 51 
J 0
(-5059 2300);
DISPLAY 0.638298 (-5059 2300);
PAINT MONO (-5059 2300);
FORCEPROP 2 LAST $XR8 52 
J 0
(-5149 2300);
DISPLAY 0.638298 (-5149 2300);
PAINT MONO (-5149 2300);
FORCEPROP 2 LAST $XR9 53 
J 0
(-5239 2300);
DISPLAY 0.638298 (-5239 2300);
PAINT MONO (-5239 2300);
FORCEPROP 2 LAST $XR10 54 
J 0
(-4429 2264);
DISPLAY 0.638298 (-4429 2264);
PAINT MONO (-4429 2264);
FORCEPROP 2 LAST $XR11 77 
J 0
(-4519 2264);
DISPLAY 0.638298 (-4519 2264);
PAINT MONO (-4519 2264);
FORCEPROP 2 LAST $XR12 78 
J 0
(-4609 2264);
DISPLAY 0.638298 (-4609 2264);
PAINT MONO (-4609 2264);
FORCEPROP 2 LAST $XR13 79 
J 0
(-4699 2264);
DISPLAY 0.638298 (-4699 2264);
PAINT MONO (-4699 2264);
FORCEPROP 2 LAST $XR14 80 
J 0
(-4789 2264);
DISPLAY 0.638298 (-4789 2264);
PAINT MONO (-4789 2264);
FORCEPROP 2 LAST $XR15 81 
J 0
(-4879 2264);
DISPLAY 0.638298 (-4879 2264);
PAINT MONO (-4879 2264);
FORCEPROP 2 LAST $XR16 82 
J 0
(-4969 2264);
DISPLAY 0.638298 (-4969 2264);
PAINT MONO (-4969 2264);
FORCEPROP 2 LAST $XR17 83 
J 0
(-5059 2264);
DISPLAY 0.638298 (-5059 2264);
PAINT MONO (-5059 2264);
FORCEPROP 2 LAST $XR18 84 
J 0
(-5149 2264);
DISPLAY 0.638298 (-5149 2264);
PAINT MONO (-5149 2264);
FORCEPROP 2 LAST $XR19 85 
J 0
(-4429 2336);
DISPLAY 0.638298 (-4429 2336);
PAINT MONO (-4429 2336);
FORCEPROP 2 LAST $XR20 86 
J 0
(-4519 2336);
DISPLAY 0.638298 (-4519 2336);
PAINT MONO (-4519 2336);
FORCEPROP 2 LAST $XR21 87 
J 0
(-4609 2336);
DISPLAY 0.638298 (-4609 2336);
PAINT MONO (-4609 2336);
FORCEPROP 2 LAST $XR22 88 
J 0
(-4699 2336);
DISPLAY 0.638298 (-4699 2336);
PAINT MONO (-4699 2336);
FORCEPROP 2 LAST $XR23 94 
J 0
(-4789 2336);
DISPLAY 0.638298 (-4789 2336);
PAINT MONO (-4789 2336);
FORCEPROP 2 LAST CDS_LIB mstr_standard
J 0
(-4175 2300);
DISPLAY 0.787234 (-4175 2300);
PAINT MONO (-4175 2300);
DISPLAY INVISIBLE (-4175 2300);
FORCEPROP 1 LAST OFFPAGE TRUE
J 0
(-3850 2175);
DISPLAY 1.404255 (-3850 2175);
PAINT GREEN (-3850 2175);
DISPLAY INVISIBLE (-3850 2175);
FORCEPROP 1 LAST COMMENT_BODY TRUE
J 0
(-4075 2225);
DISPLAY 1.404255 (-4075 2225);
PAINT GREEN (-4075 2225);
DISPLAY INVISIBLE (-4075 2225);
FORCEPROP 2 LAST PATH I177
J 0
(-4450 2350);
PAINT ORANGE (-4450 2350);
DISPLAY INVISIBLE (-4450 2350);
FORCEADD GND..1
(-4600 1000);
FORCEPROP 3 LASTPIN (-4600 1050) SIG_NAME GND\g
J 0
(-4590 1060);
DISPLAY 0.659574 (-4590 1060);
PAINT MONO (-4590 1060);
DISPLAY INVISIBLE (-4590 1060);
FORCEPROP 1 LAST VOLTAGE 0
J 0
(-4600 1000);
PAINT SKYBLUE (-4600 1000);
DISPLAY INVISIBLE (-4600 1000);
FORCEPROP 2 LAST CDS_LIB mstr_symbols
J 0
(-4600 1000);
PAINT ORANGE (-4600 1000);
DISPLAY INVISIBLE (-4600 1000);
FORCEPROP 1 LAST SIZE 1B
J 0
(-4525 950);
DISPLAY 1.787234 (-4525 950);
PAINT GREEN (-4525 950);
DISPLAY INVISIBLE (-4525 950);
FORCEPROP 2 LAST BOM_COST MEM
J 0
(-4600 1005);
PAINT ORANGE (-4600 1005);
DISPLAY INVISIBLE (-4600 1005);
FORCEPROP 1 LAST BODY_TYPE PLUMBING
J 0
(-4645 957);
DISPLAY 0.340426 (-4645 957);
PAINT GREEN (-4645 957);
DISPLAY INVISIBLE (-4645 957);
FORCEPROP 1 LAST PATH I178
J 0
(-4525 1000);
DISPLAY 1.404255 (-4525 1000);
PAINT GREEN (-4525 1000);
DISPLAY INVISIBLE (-4525 1000);
FORCEPROP 2 LAST ROOM DDR4_CH_A
J 0
(-4600 1005);
PAINT ORANGE (-4600 1005);
DISPLAY INVISIBLE (-4600 1005);
FORCEPROP 1 LAST HDL_POWER GND
J 0
(-4600 1150);
DISPLAY 1.404255 (-4600 1150);
PAINT GREEN (-4600 1150);
DISPLAY INVISIBLE (-4600 1150);
FORCEADD CAP_A..1
R 2
(-4600 1250);
FORCEPROP 1 LAST LOCATION C4G3
J 2
(-4650 1350);
DISPLAY 0.617021 (-4650 1350);
PAINT AQUA (-4650 1350);
FORCEPROP 1 LAST PART_NUMBER A36096-045
J 2
(-4650 1100);
DISPLAY 0.617021 (-4650 1100);
PAINT BLUE (-4650 1100);
FORCEPROP 1 LAST VALUE 0.01UF
J 2
(-4650 1300);
DISPLAY 0.617021 (-4650 1300);
PAINT SKYBLUE (-4650 1300);
FORCEPROP 1 LAST TOLERANCE 10%
J 2
(-4650 1200);
DISPLAY 0.617021 (-4650 1200);
PAINT SKYBLUE (-4650 1200);
FORCEPROP 1 LAST PACK_TYPE 0402V
J 2
(-4650 1050);
DISPLAY 0.617021 (-4650 1050);
PAINT SKYBLUE (-4650 1050);
FORCEPROP 1 LAST VOLTAGE 25V
J 2
(-4650 1250);
DISPLAY 0.617021 (-4650 1250);
PAINT SKYBLUE (-4650 1250);
FORCEPROP 1 LAST MATERIAL X7R
J 2
(-4650 1150);
DISPLAY 0.617021 (-4650 1150);
PAINT SKYBLUE (-4650 1150);
FORCEPROP 2 LAST CDS_LOCATION C4G3
J 2
(-4650 1350);
DISPLAY 0.617021 (-4650 1350);
PAINT AQUA (-4650 1350);
DISPLAY INVISIBLE (-4650 1350);
FORCEPROP 2 LAST BOM_COST MEM
J 0
(-4600 1250);
PAINT ORANGE (-4600 1250);
DISPLAY INVISIBLE (-4600 1250);
FORCEPROP 2 LAST CDS_LIB dev_discrete
J 0
(-4600 1250);
PAINT ORANGE (-4600 1250);
DISPLAY INVISIBLE (-4600 1250);
FORCEPROP 2 LAST CDS_SEC 1
J 2
(-4650 1450);
PAINT MONO (-4650 1450);
DISPLAY INVISIBLE (-4650 1450);
FORCEPROP 2 LAST $SEC 1
J 0
(-4650 1450);
PAINT MONO (-4650 1450);
DISPLAY INVISIBLE (-4650 1450);
FORCEPROP 1 LAST PATH I179
J 2
(-4650 1400);
DISPLAY 0.978723 (-4650 1400);
PAINT WHITE (-4650 1400);
DISPLAY INVISIBLE (-4650 1400);
FORCEPROP 2 LAST ROOM DDR4_CH_A
J 0
(-4600 1250);
PAINT ORANGE (-4600 1250);
DISPLAY INVISIBLE (-4600 1250);
FORCEPROP 1 LASTPIN (-4600 1350) $PN 1
J 2
(-4610 1330);
DISPLAY 0.787234 (-4610 1330);
PAINT ORANGE (-4610 1330);
DISPLAY INVISIBLE (-4610 1330);
FORCEPROP 1 LASTPIN (-4600 1150) $PN 2
J 2
(-4610 1130);
DISPLAY 0.787234 (-4610 1130);
PAINT ORANGE (-4610 1130);
DISPLAY INVISIBLE (-4610 1130);
FORCEADD TAP..6
R 2
(700 4550);
FORCEPROP 3 LASTPIN (650 4550) SIG_NAME M_B_DQS_DP<11>
J 0
(660 4560);
DISPLAY 0.659574 (660 4560);
PAINT MONO (660 4560);
DISPLAY INVISIBLE (660 4560);
FORCEPROP 1 LASTPIN (650 4550) BN 11
J 2
(700 4560);
DISPLAY 0.617021 (700 4560);
PAINT PINK (700 4560);
FORCEPROP 2 LAST CDS_LIB mstr_standard
J 0
(700 4550);
DISPLAY 0.787234 (700 4550);
PAINT MONO (700 4550);
DISPLAY INVISIBLE (700 4550);
FORCEPROP 1 LAST BODY_TYPE PLUMBING
J 2
(700 4500);
DISPLAY 1.234043 (700 4500);
PAINT GREEN (700 4500);
DISPLAY INVISIBLE (700 4500);
FORCEPROP 1 LAST HDL_TAP TRUE
J 2
(375 4425);
DISPLAY 1.234043 (375 4425);
PAINT GREEN (375 4425);
DISPLAY INVISIBLE (375 4425);
FORCEPROP 1 LAST PATH I18
J 2
(700 4550);
DISPLAY 0.936170 (700 4550);
PAINT GREEN (700 4550);
DISPLAY INVISIBLE (700 4550);
FORCEADD PVPP_ABC..1
(-650 3000);
FORCEPROP 3 LASTPIN (-650 2950) SIG_NAME PVPP_ABC\g
J 0
(-640 2960);
DISPLAY 0.659574 (-640 2960);
PAINT MONO (-640 2960);
DISPLAY INVISIBLE (-640 2960);
FORCEPROP 1 LAST VOLTAGE 2.5V
J 0
(-695 2957);
DISPLAY 0.340426 (-695 2957);
PAINT SKYBLUE (-695 2957);
DISPLAY INVISIBLE (-695 2957);
FORCEPROP 0 LAST BOM_COST MEM
J 0
(-650 3100);
PAINT ORANGE (-650 3100);
DISPLAY INVISIBLE (-650 3100);
FORCEPROP 2 LAST CDS_LIB mstr_symbols
J 0
(-650 3000);
PAINT ORANGE (-650 3000);
DISPLAY INVISIBLE (-650 3000);
FORCEPROP 1 LAST BODY_TYPE PLUMBING
J 0
(-695 2957);
DISPLAY 0.340426 (-695 2957);
PAINT GREEN (-695 2957);
DISPLAY INVISIBLE (-695 2957);
FORCEPROP 1 LAST PATH I180
J 0
(-600 3025);
DISPLAY 0.872340 (-600 3025);
PAINT AQUA (-600 3025);
DISPLAY INVISIBLE (-600 3025);
FORCEPROP 2 LAST ROOM DDR4_CH_A
J 0
(-650 3100);
PAINT ORANGE (-650 3100);
DISPLAY INVISIBLE (-650 3100);
FORCEPROP 1 LAST HDL_POWER PVPP_ABC
J 1
(-650 3050);
DISPLAY 0.872340 (-650 3050);
PAINT GREEN (-650 3050);
DISPLAY INVISIBLE (-650 3050);
FORCEADD PVPP_ABC..1
(-5050 1950);
FORCEPROP 3 LASTPIN (-5050 1900) SIG_NAME PVPP_ABC\g
J 0
(-5040 1910);
DISPLAY 0.659574 (-5040 1910);
PAINT MONO (-5040 1910);
DISPLAY INVISIBLE (-5040 1910);
FORCEPROP 1 LAST VOLTAGE 2.5V
J 0
(-5095 1907);
DISPLAY 0.340426 (-5095 1907);
PAINT SKYBLUE (-5095 1907);
DISPLAY INVISIBLE (-5095 1907);
FORCEPROP 0 LAST BOM_COST MEM
J 0
(-5050 2050);
PAINT ORANGE (-5050 2050);
DISPLAY INVISIBLE (-5050 2050);
FORCEPROP 2 LAST CDS_LIB mstr_symbols
J 0
(-5050 1950);
PAINT ORANGE (-5050 1950);
DISPLAY INVISIBLE (-5050 1950);
FORCEPROP 1 LAST BODY_TYPE PLUMBING
J 0
(-5095 1907);
DISPLAY 0.340426 (-5095 1907);
PAINT GREEN (-5095 1907);
DISPLAY INVISIBLE (-5095 1907);
FORCEPROP 1 LAST PATH I181
J 0
(-5000 1975);
DISPLAY 0.872340 (-5000 1975);
PAINT AQUA (-5000 1975);
DISPLAY INVISIBLE (-5000 1975);
FORCEPROP 2 LAST ROOM DDR4_CH_A
J 0
(-5050 2050);
PAINT ORANGE (-5050 2050);
DISPLAY INVISIBLE (-5050 2050);
FORCEPROP 1 LAST HDL_POWER PVPP_ABC
J 1
(-5050 2000);
DISPLAY 0.872340 (-5050 2000);
PAINT GREEN (-5050 2000);
DISPLAY INVISIBLE (-5050 2000);
FORCEADD OFFPAGE..1
(-3850 1150);
FORCEPROP 2 LAST $XR0 89 
J 0
(-4101 1150);
DISPLAY 0.638298 (-4101 1150);
PAINT MONO (-4101 1150);
FORCEPROP 2 LAST $XR1 43 
J 0
(-4191 1150);
DISPLAY 0.638298 (-4191 1150);
PAINT MONO (-4191 1150);
FORCEPROP 2 LAST $XR2 44 
J 0
(-4281 1150);
DISPLAY 0.638298 (-4281 1150);
PAINT MONO (-4281 1150);
FORCEPROP 2 LAST $XR3 46 
J 0
(-4371 1150);
DISPLAY 0.638298 (-4371 1150);
PAINT MONO (-4371 1150);
FORCEPROP 2 LAST $XR4 47 
J 0
(-4461 1150);
DISPLAY 0.638298 (-4461 1150);
PAINT MONO (-4461 1150);
FORCEPROP 2 LAST $XR5 48 
J 0
(-4551 1150);
DISPLAY 0.638298 (-4551 1150);
PAINT MONO (-4551 1150);
FORCEPROP 2 LAST CDS_LIB mstr_standard
J 0
(-3850 1150);
PAINT ORANGE (-3850 1150);
DISPLAY INVISIBLE (-3850 1150);
FORCEPROP 1 LAST OFFPAGE TRUE
J 0
(-3525 1025);
DISPLAY 0.936170 (-3525 1025);
PAINT GREEN (-3525 1025);
DISPLAY INVISIBLE (-3525 1025);
FORCEPROP 1 LAST COMMENT_BODY TRUE
J 0
(-3725 1050);
DISPLAY 0.936170 (-3725 1050);
PAINT GREEN (-3725 1050);
DISPLAY INVISIBLE (-3725 1050);
FORCEPROP 2 LAST PATH I182
J 0
(-3800 1225);
PAINT ORANGE (-3800 1225);
DISPLAY INVISIBLE (-3800 1225);
FORCEADD P12V_NVDIMM_ABC..1
(750 3075);
FORCEPROP 3 LASTPIN (750 3025) SIG_NAME P12V_NVDIMM_ABC\g
J 0
(760 3035);
DISPLAY 0.659574 (760 3035);
PAINT MONO (760 3035);
DISPLAY INVISIBLE (760 3035);
FORCEPROP 1 LAST VOLTAGE 12.0
J 0
(705 3032);
DISPLAY 0.340426 (705 3032);
PAINT SKYBLUE (705 3032);
DISPLAY INVISIBLE (705 3032);
FORCEPROP 2 LAST CDS_LIB mstr_symbols
J 0
(750 3075);
PAINT ORANGE (750 3075);
DISPLAY INVISIBLE (750 3075);
FORCEPROP 1 LAST BODY_TYPE PLUMBING
J 0
(705 3032);
DISPLAY 0.340426 (705 3032);
PAINT GREEN (705 3032);
DISPLAY INVISIBLE (705 3032);
FORCEPROP 1 LAST PATH I183
J 0
(800 3100);
DISPLAY 0.872340 (800 3100);
PAINT AQUA (800 3100);
DISPLAY INVISIBLE (800 3100);
FORCEPROP 1 LAST HDL_POWER P12V_NVDIMM_ABC
J 1
(750 3100);
DISPLAY 0.872340 (750 3100);
PAINT GREEN (750 3100);
DISPLAY INVISIBLE (750 3100);
FORCEADD TAP..6
R 2
(900 4400);
FORCEPROP 3 LASTPIN (850 4400) SIG_NAME M_B_DQS_DN<10>
J 0
(860 4410);
DISPLAY 0.659574 (860 4410);
PAINT MONO (860 4410);
DISPLAY INVISIBLE (860 4410);
FORCEPROP 1 LASTPIN (850 4400) BN 10
J 2
(900 4410);
DISPLAY 0.617021 (900 4410);
PAINT PINK (900 4410);
FORCEPROP 2 LAST CDS_LIB mstr_standard
J 0
(900 4400);
DISPLAY 0.787234 (900 4400);
PAINT MONO (900 4400);
DISPLAY INVISIBLE (900 4400);
FORCEPROP 1 LAST BODY_TYPE PLUMBING
J 2
(900 4350);
DISPLAY 1.234043 (900 4350);
PAINT GREEN (900 4350);
DISPLAY INVISIBLE (900 4350);
FORCEPROP 1 LAST HDL_TAP TRUE
J 2
(575 4275);
DISPLAY 1.234043 (575 4275);
PAINT GREEN (575 4275);
DISPLAY INVISIBLE (575 4275);
FORCEPROP 1 LAST PATH I19
J 2
(900 4400);
DISPLAY 0.936170 (900 4400);
PAINT GREEN (900 4400);
DISPLAY INVISIBLE (900 4400);
FORCEADD OFFPAGE..3
(1600 5150);
FORCEPROP 2 LAST $XR0 24 
J 0
(1814 5150);
DISPLAY 0.638298 (1814 5150);
PAINT MONO (1814 5150);
FORCEPROP 2 LAST $XR1 46 
J 0
(1904 5150);
DISPLAY 0.638298 (1904 5150);
PAINT MONO (1904 5150);
FORCEPROP 2 LAST CDS_LIB mstr_standard
J 0
(1600 5150);
DISPLAY 0.787234 (1600 5150);
PAINT MONO (1600 5150);
DISPLAY INVISIBLE (1600 5150);
FORCEPROP 1 LAST OFFPAGE TRUE
J 0
(1925 5025);
DISPLAY 0.936170 (1925 5025);
PAINT GREEN (1925 5025);
DISPLAY INVISIBLE (1925 5025);
FORCEPROP 1 LAST COMMENT_BODY TRUE
J 0
(1550 5050);
DISPLAY 0.936170 (1550 5050);
PAINT GREEN (1550 5050);
DISPLAY INVISIBLE (1550 5050);
FORCEPROP 2 LAST PATH I2
J 0
(1800 5225);
DISPLAY 0.787234 (1800 5225);
PAINT MONO (1800 5225);
DISPLAY INVISIBLE (1800 5225);
FORCEADD TAP..6
R 2
(900 4500);
FORCEPROP 3 LASTPIN (850 4500) SIG_NAME M_B_DQS_DN<11>
J 0
(860 4510);
DISPLAY 0.659574 (860 4510);
PAINT MONO (860 4510);
DISPLAY INVISIBLE (860 4510);
FORCEPROP 1 LASTPIN (850 4500) BN 11
J 2
(900 4510);
DISPLAY 0.617021 (900 4510);
PAINT PINK (900 4510);
FORCEPROP 2 LAST CDS_LIB mstr_standard
J 0
(900 4500);
DISPLAY 0.787234 (900 4500);
PAINT MONO (900 4500);
DISPLAY INVISIBLE (900 4500);
FORCEPROP 1 LAST BODY_TYPE PLUMBING
J 2
(900 4450);
DISPLAY 1.234043 (900 4450);
PAINT GREEN (900 4450);
DISPLAY INVISIBLE (900 4450);
FORCEPROP 1 LAST HDL_TAP TRUE
J 2
(575 4375);
DISPLAY 1.234043 (575 4375);
PAINT GREEN (575 4375);
DISPLAY INVISIBLE (575 4375);
FORCEPROP 1 LAST PATH I20
J 2
(900 4500);
DISPLAY 0.936170 (900 4500);
PAINT GREEN (900 4500);
DISPLAY INVISIBLE (900 4500);
FORCEADD TAP..6
R 2
(900 4300);
FORCEPROP 3 LASTPIN (850 4300) SIG_NAME M_B_DQS_DN<9>
J 0
(860 4310);
DISPLAY 0.659574 (860 4310);
PAINT MONO (860 4310);
DISPLAY INVISIBLE (860 4310);
FORCEPROP 1 LASTPIN (850 4300) BN 9
J 2
(900 4310);
DISPLAY 0.617021 (900 4310);
PAINT PINK (900 4310);
FORCEPROP 2 LAST CDS_LIB mstr_standard
J 0
(900 4300);
DISPLAY 0.787234 (900 4300);
PAINT MONO (900 4300);
DISPLAY INVISIBLE (900 4300);
FORCEPROP 1 LAST BODY_TYPE PLUMBING
J 2
(900 4250);
DISPLAY 1.234043 (900 4250);
PAINT GREEN (900 4250);
DISPLAY INVISIBLE (900 4250);
FORCEPROP 1 LAST HDL_TAP TRUE
J 2
(575 4175);
DISPLAY 1.234043 (575 4175);
PAINT GREEN (575 4175);
DISPLAY INVISIBLE (575 4175);
FORCEPROP 1 LAST PATH I21
J 2
(900 4300);
DISPLAY 0.936170 (900 4300);
PAINT GREEN (900 4300);
DISPLAY INVISIBLE (900 4300);
FORCEADD TAP..6
R 2
(700 4450);
FORCEPROP 3 LASTPIN (650 4450) SIG_NAME M_B_DQS_DP<10>
J 0
(660 4460);
DISPLAY 0.659574 (660 4460);
PAINT MONO (660 4460);
DISPLAY INVISIBLE (660 4460);
FORCEPROP 1 LASTPIN (650 4450) BN 10
J 2
(700 4460);
DISPLAY 0.617021 (700 4460);
PAINT PINK (700 4460);
FORCEPROP 2 LAST CDS_LIB mstr_standard
J 0
(700 4450);
DISPLAY 0.787234 (700 4450);
PAINT MONO (700 4450);
DISPLAY INVISIBLE (700 4450);
FORCEPROP 1 LAST BODY_TYPE PLUMBING
J 2
(700 4400);
DISPLAY 1.234043 (700 4400);
PAINT GREEN (700 4400);
DISPLAY INVISIBLE (700 4400);
FORCEPROP 1 LAST HDL_TAP TRUE
J 2
(375 4325);
DISPLAY 1.234043 (375 4325);
PAINT GREEN (375 4325);
DISPLAY INVISIBLE (375 4325);
FORCEPROP 1 LAST PATH I22
J 2
(700 4450);
DISPLAY 0.936170 (700 4450);
PAINT GREEN (700 4450);
DISPLAY INVISIBLE (700 4450);
FORCEADD TAP..6
R 2
(700 4350);
FORCEPROP 3 LASTPIN (650 4350) SIG_NAME M_B_DQS_DP<9>
J 0
(660 4360);
DISPLAY 0.659574 (660 4360);
PAINT MONO (660 4360);
DISPLAY INVISIBLE (660 4360);
FORCEPROP 1 LASTPIN (650 4350) BN 9
J 2
(700 4360);
DISPLAY 0.617021 (700 4360);
PAINT PINK (700 4360);
FORCEPROP 2 LAST CDS_LIB mstr_standard
J 0
(700 4350);
DISPLAY 0.787234 (700 4350);
PAINT MONO (700 4350);
DISPLAY INVISIBLE (700 4350);
FORCEPROP 1 LAST BODY_TYPE PLUMBING
J 2
(700 4300);
DISPLAY 1.234043 (700 4300);
PAINT GREEN (700 4300);
DISPLAY INVISIBLE (700 4300);
FORCEPROP 1 LAST HDL_TAP TRUE
J 2
(375 4225);
DISPLAY 1.234043 (375 4225);
PAINT GREEN (375 4225);
DISPLAY INVISIBLE (375 4225);
FORCEPROP 1 LAST PATH I23
J 2
(700 4350);
DISPLAY 0.936170 (700 4350);
PAINT GREEN (700 4350);
DISPLAY INVISIBLE (700 4350);
FORCEADD TAP..6
R 2
(900 4100);
FORCEPROP 3 LASTPIN (850 4100) SIG_NAME M_B_DQS_DN<7>
J 0
(860 4110);
DISPLAY 0.659574 (860 4110);
PAINT MONO (860 4110);
DISPLAY INVISIBLE (860 4110);
FORCEPROP 1 LASTPIN (850 4100) BN 7
J 2
(900 4110);
DISPLAY 0.617021 (900 4110);
PAINT PINK (900 4110);
FORCEPROP 2 LAST CDS_LIB mstr_standard
J 0
(900 4100);
DISPLAY 0.787234 (900 4100);
PAINT MONO (900 4100);
DISPLAY INVISIBLE (900 4100);
FORCEPROP 1 LAST BODY_TYPE PLUMBING
J 2
(900 4050);
DISPLAY 1.234043 (900 4050);
PAINT GREEN (900 4050);
DISPLAY INVISIBLE (900 4050);
FORCEPROP 1 LAST HDL_TAP TRUE
J 2
(575 3975);
DISPLAY 1.234043 (575 3975);
PAINT GREEN (575 3975);
DISPLAY INVISIBLE (575 3975);
FORCEPROP 1 LAST PATH I24
J 2
(900 4100);
DISPLAY 0.936170 (900 4100);
PAINT GREEN (900 4100);
DISPLAY INVISIBLE (900 4100);
FORCEADD TAP..6
R 2
(900 4200);
FORCEPROP 3 LASTPIN (850 4200) SIG_NAME M_B_DQS_DN<8>
J 0
(860 4210);
DISPLAY 0.659574 (860 4210);
PAINT MONO (860 4210);
DISPLAY INVISIBLE (860 4210);
FORCEPROP 1 LASTPIN (850 4200) BN 8
J 2
(900 4210);
DISPLAY 0.617021 (900 4210);
PAINT PINK (900 4210);
FORCEPROP 2 LAST CDS_LIB mstr_standard
J 0
(900 4200);
DISPLAY 0.787234 (900 4200);
PAINT MONO (900 4200);
DISPLAY INVISIBLE (900 4200);
FORCEPROP 1 LAST BODY_TYPE PLUMBING
J 2
(900 4150);
DISPLAY 1.234043 (900 4150);
PAINT GREEN (900 4150);
DISPLAY INVISIBLE (900 4150);
FORCEPROP 1 LAST HDL_TAP TRUE
J 2
(575 4075);
DISPLAY 1.234043 (575 4075);
PAINT GREEN (575 4075);
DISPLAY INVISIBLE (575 4075);
FORCEPROP 1 LAST PATH I25
J 2
(900 4200);
DISPLAY 0.936170 (900 4200);
PAINT GREEN (900 4200);
DISPLAY INVISIBLE (900 4200);
FORCEADD TAP..6
R 2
(700 4250);
FORCEPROP 3 LASTPIN (650 4250) SIG_NAME M_B_DQS_DP<8>
J 0
(660 4260);
DISPLAY 0.659574 (660 4260);
PAINT MONO (660 4260);
DISPLAY INVISIBLE (660 4260);
FORCEPROP 1 LASTPIN (650 4250) BN 8
J 2
(700 4260);
DISPLAY 0.617021 (700 4260);
PAINT PINK (700 4260);
FORCEPROP 2 LAST CDS_LIB mstr_standard
J 0
(700 4250);
DISPLAY 0.787234 (700 4250);
PAINT MONO (700 4250);
DISPLAY INVISIBLE (700 4250);
FORCEPROP 1 LAST BODY_TYPE PLUMBING
J 2
(700 4200);
DISPLAY 1.234043 (700 4200);
PAINT GREEN (700 4200);
DISPLAY INVISIBLE (700 4200);
FORCEPROP 1 LAST HDL_TAP TRUE
J 2
(375 4125);
DISPLAY 1.234043 (375 4125);
PAINT GREEN (375 4125);
DISPLAY INVISIBLE (375 4125);
FORCEPROP 1 LAST PATH I26
J 2
(700 4250);
DISPLAY 0.936170 (700 4250);
PAINT GREEN (700 4250);
DISPLAY INVISIBLE (700 4250);
FORCEADD TAP..6
R 2
(700 4150);
FORCEPROP 3 LASTPIN (650 4150) SIG_NAME M_B_DQS_DP<7>
J 0
(660 4160);
DISPLAY 0.659574 (660 4160);
PAINT MONO (660 4160);
DISPLAY INVISIBLE (660 4160);
FORCEPROP 1 LASTPIN (650 4150) BN 7
J 2
(700 4160);
DISPLAY 0.617021 (700 4160);
PAINT PINK (700 4160);
FORCEPROP 2 LAST CDS_LIB mstr_standard
J 0
(700 4150);
DISPLAY 0.787234 (700 4150);
PAINT MONO (700 4150);
DISPLAY INVISIBLE (700 4150);
FORCEPROP 1 LAST BODY_TYPE PLUMBING
J 2
(700 4100);
DISPLAY 1.234043 (700 4100);
PAINT GREEN (700 4100);
DISPLAY INVISIBLE (700 4100);
FORCEPROP 1 LAST HDL_TAP TRUE
J 2
(375 4025);
DISPLAY 1.234043 (375 4025);
PAINT GREEN (375 4025);
DISPLAY INVISIBLE (375 4025);
FORCEPROP 1 LAST PATH I27
J 2
(700 4150);
DISPLAY 0.936170 (700 4150);
PAINT GREEN (700 4150);
DISPLAY INVISIBLE (700 4150);
FORCEADD TAP..6
R 2
(700 4050);
FORCEPROP 3 LASTPIN (650 4050) SIG_NAME M_B_DQS_DP<6>
J 0
(660 4060);
DISPLAY 0.659574 (660 4060);
PAINT MONO (660 4060);
DISPLAY INVISIBLE (660 4060);
FORCEPROP 1 LASTPIN (650 4050) BN 6
J 2
(700 4060);
DISPLAY 0.617021 (700 4060);
PAINT PINK (700 4060);
FORCEPROP 2 LAST CDS_LIB mstr_standard
J 0
(700 4050);
DISPLAY 0.787234 (700 4050);
PAINT MONO (700 4050);
DISPLAY INVISIBLE (700 4050);
FORCEPROP 1 LAST BODY_TYPE PLUMBING
J 2
(700 4000);
DISPLAY 1.234043 (700 4000);
PAINT GREEN (700 4000);
DISPLAY INVISIBLE (700 4000);
FORCEPROP 1 LAST HDL_TAP TRUE
J 2
(375 3925);
DISPLAY 1.234043 (375 3925);
PAINT GREEN (375 3925);
DISPLAY INVISIBLE (375 3925);
FORCEPROP 1 LAST PATH I28
J 2
(700 4050);
DISPLAY 0.936170 (700 4050);
PAINT GREEN (700 4050);
DISPLAY INVISIBLE (700 4050);
FORCEADD TAP..6
R 2
(900 3900);
FORCEPROP 3 LASTPIN (850 3900) SIG_NAME M_B_DQS_DN<5>
J 0
(860 3910);
DISPLAY 0.659574 (860 3910);
PAINT MONO (860 3910);
DISPLAY INVISIBLE (860 3910);
FORCEPROP 1 LASTPIN (850 3900) BN 5
J 2
(900 3910);
DISPLAY 0.617021 (900 3910);
PAINT PINK (900 3910);
FORCEPROP 2 LAST CDS_LIB mstr_standard
J 0
(900 3900);
DISPLAY 0.787234 (900 3900);
PAINT MONO (900 3900);
DISPLAY INVISIBLE (900 3900);
FORCEPROP 1 LAST BODY_TYPE PLUMBING
J 2
(900 3850);
DISPLAY 1.234043 (900 3850);
PAINT GREEN (900 3850);
DISPLAY INVISIBLE (900 3850);
FORCEPROP 1 LAST HDL_TAP TRUE
J 2
(575 3775);
DISPLAY 1.234043 (575 3775);
PAINT GREEN (575 3775);
DISPLAY INVISIBLE (575 3775);
FORCEPROP 1 LAST PATH I29
J 2
(900 3900);
DISPLAY 0.936170 (900 3900);
PAINT GREEN (900 3900);
DISPLAY INVISIBLE (900 3900);
FORCEADD TAP..6
R 2
(900 5100);
FORCEPROP 3 LASTPIN (850 5100) SIG_NAME M_B_DQS_DN<17>
J 0
(860 5110);
DISPLAY 0.659574 (860 5110);
PAINT MONO (860 5110);
DISPLAY INVISIBLE (860 5110);
FORCEPROP 1 LASTPIN (850 5100) BN 17
J 2
(900 5110);
DISPLAY 0.617021 (900 5110);
PAINT PINK (900 5110);
FORCEPROP 2 LAST CDS_LIB mstr_standard
J 2
(900 5100);
DISPLAY 0.787234 (900 5100);
PAINT MONO (900 5100);
DISPLAY INVISIBLE (900 5100);
FORCEPROP 1 LAST BODY_TYPE PLUMBING
J 2
(900 5050);
DISPLAY 1.234043 (900 5050);
PAINT GREEN (900 5050);
DISPLAY INVISIBLE (900 5050);
FORCEPROP 1 LAST HDL_TAP TRUE
J 2
(575 4975);
DISPLAY 1.234043 (575 4975);
PAINT GREEN (575 4975);
DISPLAY INVISIBLE (575 4975);
FORCEPROP 1 LAST PATH I3
J 2
(900 5100);
DISPLAY 0.936170 (900 5100);
PAINT GREEN (900 5100);
DISPLAY INVISIBLE (900 5100);
FORCEADD TAP..6
R 2
(900 4000);
FORCEPROP 3 LASTPIN (850 4000) SIG_NAME M_B_DQS_DN<6>
J 0
(860 4010);
DISPLAY 0.659574 (860 4010);
PAINT MONO (860 4010);
DISPLAY INVISIBLE (860 4010);
FORCEPROP 1 LASTPIN (850 4000) BN 6
J 2
(900 4010);
DISPLAY 0.617021 (900 4010);
PAINT PINK (900 4010);
FORCEPROP 2 LAST CDS_LIB mstr_standard
J 0
(900 4000);
DISPLAY 0.787234 (900 4000);
PAINT MONO (900 4000);
DISPLAY INVISIBLE (900 4000);
FORCEPROP 1 LAST BODY_TYPE PLUMBING
J 2
(900 3950);
DISPLAY 1.234043 (900 3950);
PAINT GREEN (900 3950);
DISPLAY INVISIBLE (900 3950);
FORCEPROP 1 LAST HDL_TAP TRUE
J 2
(575 3875);
DISPLAY 1.234043 (575 3875);
PAINT GREEN (575 3875);
DISPLAY INVISIBLE (575 3875);
FORCEPROP 1 LAST PATH I30
J 2
(900 4000);
DISPLAY 0.936170 (900 4000);
PAINT GREEN (900 4000);
DISPLAY INVISIBLE (900 4000);
FORCEADD TAP..6
R 2
(900 3800);
FORCEPROP 3 LASTPIN (850 3800) SIG_NAME M_B_DQS_DN<4>
J 0
(860 3810);
DISPLAY 0.659574 (860 3810);
PAINT MONO (860 3810);
DISPLAY INVISIBLE (860 3810);
FORCEPROP 1 LASTPIN (850 3800) BN 4
J 2
(900 3810);
DISPLAY 0.617021 (900 3810);
PAINT PINK (900 3810);
FORCEPROP 2 LAST CDS_LIB mstr_standard
J 0
(900 3800);
DISPLAY 0.787234 (900 3800);
PAINT MONO (900 3800);
DISPLAY INVISIBLE (900 3800);
FORCEPROP 1 LAST BODY_TYPE PLUMBING
J 2
(900 3750);
DISPLAY 1.234043 (900 3750);
PAINT GREEN (900 3750);
DISPLAY INVISIBLE (900 3750);
FORCEPROP 1 LAST HDL_TAP TRUE
J 2
(575 3675);
DISPLAY 1.234043 (575 3675);
PAINT GREEN (575 3675);
DISPLAY INVISIBLE (575 3675);
FORCEPROP 1 LAST PATH I31
J 2
(900 3800);
DISPLAY 0.936170 (900 3800);
PAINT GREEN (900 3800);
DISPLAY INVISIBLE (900 3800);
FORCEADD TAP..6
R 2
(700 3950);
FORCEPROP 3 LASTPIN (650 3950) SIG_NAME M_B_DQS_DP<5>
J 0
(660 3960);
DISPLAY 0.659574 (660 3960);
PAINT MONO (660 3960);
DISPLAY INVISIBLE (660 3960);
FORCEPROP 1 LASTPIN (650 3950) BN 5
J 2
(700 3960);
DISPLAY 0.617021 (700 3960);
PAINT PINK (700 3960);
FORCEPROP 2 LAST CDS_LIB mstr_standard
J 0
(700 3950);
DISPLAY 0.787234 (700 3950);
PAINT MONO (700 3950);
DISPLAY INVISIBLE (700 3950);
FORCEPROP 1 LAST BODY_TYPE PLUMBING
J 2
(700 3900);
DISPLAY 1.234043 (700 3900);
PAINT GREEN (700 3900);
DISPLAY INVISIBLE (700 3900);
FORCEPROP 1 LAST HDL_TAP TRUE
J 2
(375 3825);
DISPLAY 1.234043 (375 3825);
PAINT GREEN (375 3825);
DISPLAY INVISIBLE (375 3825);
FORCEPROP 1 LAST PATH I32
J 2
(700 3950);
DISPLAY 0.936170 (700 3950);
PAINT GREEN (700 3950);
DISPLAY INVISIBLE (700 3950);
FORCEADD TAP..6
R 2
(700 3850);
FORCEPROP 3 LASTPIN (650 3850) SIG_NAME M_B_DQS_DP<4>
J 0
(660 3860);
DISPLAY 0.659574 (660 3860);
PAINT MONO (660 3860);
DISPLAY INVISIBLE (660 3860);
FORCEPROP 1 LASTPIN (650 3850) BN 4
J 2
(700 3860);
DISPLAY 0.617021 (700 3860);
PAINT PINK (700 3860);
FORCEPROP 2 LAST CDS_LIB mstr_standard
J 0
(700 3850);
DISPLAY 0.787234 (700 3850);
PAINT MONO (700 3850);
DISPLAY INVISIBLE (700 3850);
FORCEPROP 1 LAST BODY_TYPE PLUMBING
J 2
(700 3800);
DISPLAY 1.234043 (700 3800);
PAINT GREEN (700 3800);
DISPLAY INVISIBLE (700 3800);
FORCEPROP 1 LAST HDL_TAP TRUE
J 2
(375 3725);
DISPLAY 1.234043 (375 3725);
PAINT GREEN (375 3725);
DISPLAY INVISIBLE (375 3725);
FORCEPROP 1 LAST PATH I33
J 2
(700 3850);
DISPLAY 0.936170 (700 3850);
PAINT GREEN (700 3850);
DISPLAY INVISIBLE (700 3850);
FORCEADD TAP..6
R 2
(700 3750);
FORCEPROP 3 LASTPIN (650 3750) SIG_NAME M_B_DQS_DP<3>
J 0
(660 3760);
DISPLAY 0.659574 (660 3760);
PAINT MONO (660 3760);
DISPLAY INVISIBLE (660 3760);
FORCEPROP 1 LASTPIN (650 3750) BN 3
J 2
(700 3760);
DISPLAY 0.617021 (700 3760);
PAINT PINK (700 3760);
FORCEPROP 2 LAST CDS_LIB mstr_standard
J 0
(700 3750);
DISPLAY 0.787234 (700 3750);
PAINT MONO (700 3750);
DISPLAY INVISIBLE (700 3750);
FORCEPROP 1 LAST BODY_TYPE PLUMBING
J 2
(700 3700);
DISPLAY 1.234043 (700 3700);
PAINT GREEN (700 3700);
DISPLAY INVISIBLE (700 3700);
FORCEPROP 1 LAST HDL_TAP TRUE
J 2
(375 3625);
DISPLAY 1.234043 (375 3625);
PAINT GREEN (375 3625);
DISPLAY INVISIBLE (375 3625);
FORCEPROP 1 LAST PATH I34
J 2
(700 3750);
DISPLAY 0.936170 (700 3750);
PAINT GREEN (700 3750);
DISPLAY INVISIBLE (700 3750);
FORCEADD TAP..6
R 2
(900 3500);
FORCEPROP 3 LASTPIN (850 3500) SIG_NAME M_B_DQS_DN<1>
J 0
(860 3510);
DISPLAY 0.659574 (860 3510);
PAINT MONO (860 3510);
DISPLAY INVISIBLE (860 3510);
FORCEPROP 1 LASTPIN (850 3500) BN 1
J 2
(900 3510);
DISPLAY 0.617021 (900 3510);
PAINT PINK (900 3510);
FORCEPROP 2 LAST CDS_LIB mstr_standard
J 0
(900 3500);
DISPLAY 0.787234 (900 3500);
PAINT MONO (900 3500);
DISPLAY INVISIBLE (900 3500);
FORCEPROP 1 LAST BODY_TYPE PLUMBING
J 2
(900 3450);
DISPLAY 1.234043 (900 3450);
PAINT GREEN (900 3450);
DISPLAY INVISIBLE (900 3450);
FORCEPROP 1 LAST HDL_TAP TRUE
J 2
(575 3375);
DISPLAY 1.234043 (575 3375);
PAINT GREEN (575 3375);
DISPLAY INVISIBLE (575 3375);
FORCEPROP 1 LAST PATH I35
J 2
(900 3500);
DISPLAY 0.936170 (900 3500);
PAINT GREEN (900 3500);
DISPLAY INVISIBLE (900 3500);
FORCEADD TAP..6
R 2
(900 3600);
FORCEPROP 3 LASTPIN (850 3600) SIG_NAME M_B_DQS_DN<2>
J 0
(860 3610);
DISPLAY 0.659574 (860 3610);
PAINT MONO (860 3610);
DISPLAY INVISIBLE (860 3610);
FORCEPROP 1 LASTPIN (850 3600) BN 2
J 2
(900 3610);
DISPLAY 0.617021 (900 3610);
PAINT PINK (900 3610);
FORCEPROP 2 LAST CDS_LIB mstr_standard
J 0
(900 3600);
DISPLAY 0.787234 (900 3600);
PAINT MONO (900 3600);
DISPLAY INVISIBLE (900 3600);
FORCEPROP 1 LAST BODY_TYPE PLUMBING
J 2
(900 3550);
DISPLAY 1.234043 (900 3550);
PAINT GREEN (900 3550);
DISPLAY INVISIBLE (900 3550);
FORCEPROP 1 LAST HDL_TAP TRUE
J 2
(575 3475);
DISPLAY 1.234043 (575 3475);
PAINT GREEN (575 3475);
DISPLAY INVISIBLE (575 3475);
FORCEPROP 1 LAST PATH I36
J 2
(900 3600);
DISPLAY 0.936170 (900 3600);
PAINT GREEN (900 3600);
DISPLAY INVISIBLE (900 3600);
FORCEADD TAP..6
R 2
(900 3700);
FORCEPROP 3 LASTPIN (850 3700) SIG_NAME M_B_DQS_DN<3>
J 0
(860 3710);
DISPLAY 0.659574 (860 3710);
PAINT MONO (860 3710);
DISPLAY INVISIBLE (860 3710);
FORCEPROP 1 LASTPIN (850 3700) BN 3
J 2
(900 3710);
DISPLAY 0.617021 (900 3710);
PAINT PINK (900 3710);
FORCEPROP 2 LAST CDS_LIB mstr_standard
J 0
(900 3700);
DISPLAY 0.787234 (900 3700);
PAINT MONO (900 3700);
DISPLAY INVISIBLE (900 3700);
FORCEPROP 1 LAST BODY_TYPE PLUMBING
J 2
(900 3650);
DISPLAY 1.234043 (900 3650);
PAINT GREEN (900 3650);
DISPLAY INVISIBLE (900 3650);
FORCEPROP 1 LAST HDL_TAP TRUE
J 2
(575 3575);
DISPLAY 1.234043 (575 3575);
PAINT GREEN (575 3575);
DISPLAY INVISIBLE (575 3575);
FORCEPROP 1 LAST PATH I37
J 2
(900 3700);
DISPLAY 0.936170 (900 3700);
PAINT GREEN (900 3700);
DISPLAY INVISIBLE (900 3700);
FORCEADD TAP..6
R 2
(700 3650);
FORCEPROP 3 LASTPIN (650 3650) SIG_NAME M_B_DQS_DP<2>
J 0
(660 3660);
DISPLAY 0.659574 (660 3660);
PAINT MONO (660 3660);
DISPLAY INVISIBLE (660 3660);
FORCEPROP 1 LASTPIN (650 3650) BN 2
J 2
(700 3660);
DISPLAY 0.617021 (700 3660);
PAINT PINK (700 3660);
FORCEPROP 2 LAST CDS_LIB mstr_standard
J 0
(700 3650);
DISPLAY 0.787234 (700 3650);
PAINT MONO (700 3650);
DISPLAY INVISIBLE (700 3650);
FORCEPROP 1 LAST BODY_TYPE PLUMBING
J 2
(700 3600);
DISPLAY 1.234043 (700 3600);
PAINT GREEN (700 3600);
DISPLAY INVISIBLE (700 3600);
FORCEPROP 1 LAST HDL_TAP TRUE
J 2
(375 3525);
DISPLAY 1.234043 (375 3525);
PAINT GREEN (375 3525);
DISPLAY INVISIBLE (375 3525);
FORCEPROP 1 LAST PATH I38
J 2
(700 3650);
DISPLAY 0.936170 (700 3650);
PAINT GREEN (700 3650);
DISPLAY INVISIBLE (700 3650);
FORCEADD TAP..6
R 2
(700 3550);
FORCEPROP 3 LASTPIN (650 3550) SIG_NAME M_B_DQS_DP<1>
J 0
(660 3560);
DISPLAY 0.659574 (660 3560);
PAINT MONO (660 3560);
DISPLAY INVISIBLE (660 3560);
FORCEPROP 1 LASTPIN (650 3550) BN 1
J 2
(700 3560);
DISPLAY 0.617021 (700 3560);
PAINT PINK (700 3560);
FORCEPROP 2 LAST CDS_LIB mstr_standard
J 0
(700 3550);
DISPLAY 0.787234 (700 3550);
PAINT MONO (700 3550);
DISPLAY INVISIBLE (700 3550);
FORCEPROP 1 LAST BODY_TYPE PLUMBING
J 2
(700 3500);
DISPLAY 1.234043 (700 3500);
PAINT GREEN (700 3500);
DISPLAY INVISIBLE (700 3500);
FORCEPROP 1 LAST HDL_TAP TRUE
J 2
(375 3425);
DISPLAY 1.234043 (375 3425);
PAINT GREEN (375 3425);
DISPLAY INVISIBLE (375 3425);
FORCEPROP 1 LAST PATH I39
J 2
(700 3550);
DISPLAY 0.936170 (700 3550);
PAINT GREEN (700 3550);
DISPLAY INVISIBLE (700 3550);
FORCEADD TAP..6
R 2
(700 5150);
FORCEPROP 3 LASTPIN (650 5150) SIG_NAME M_B_DQS_DP<17>
J 0
(660 5160);
DISPLAY 0.659574 (660 5160);
PAINT MONO (660 5160);
DISPLAY INVISIBLE (660 5160);
FORCEPROP 1 LASTPIN (650 5150) BN 17
J 2
(700 5160);
DISPLAY 0.617021 (700 5160);
PAINT PINK (700 5160);
FORCEPROP 2 LAST CDS_LIB mstr_standard
J 2
(700 5150);
DISPLAY 0.787234 (700 5150);
PAINT MONO (700 5150);
DISPLAY INVISIBLE (700 5150);
FORCEPROP 1 LAST BODY_TYPE PLUMBING
J 2
(700 5100);
DISPLAY 1.234043 (700 5100);
PAINT GREEN (700 5100);
DISPLAY INVISIBLE (700 5100);
FORCEPROP 1 LAST HDL_TAP TRUE
J 2
(375 5025);
DISPLAY 1.234043 (375 5025);
PAINT GREEN (375 5025);
DISPLAY INVISIBLE (375 5025);
FORCEPROP 1 LAST PATH I4
J 2
(700 5150);
DISPLAY 0.936170 (700 5150);
PAINT GREEN (700 5150);
DISPLAY INVISIBLE (700 5150);
FORCEADD TAP..6
R 2
(900 3400);
FORCEPROP 3 LASTPIN (850 3400) SIG_NAME M_B_DQS_DN<0>
J 0
(860 3410);
DISPLAY 0.659574 (860 3410);
PAINT MONO (860 3410);
DISPLAY INVISIBLE (860 3410);
FORCEPROP 1 LASTPIN (850 3400) BN 0
J 2
(900 3410);
DISPLAY 0.617021 (900 3410);
PAINT PINK (900 3410);
FORCEPROP 2 LAST CDS_LIB mstr_standard
J 0
(900 3400);
DISPLAY 0.787234 (900 3400);
PAINT MONO (900 3400);
DISPLAY INVISIBLE (900 3400);
FORCEPROP 1 LAST BODY_TYPE PLUMBING
J 2
(900 3350);
DISPLAY 1.234043 (900 3350);
PAINT GREEN (900 3350);
DISPLAY INVISIBLE (900 3350);
FORCEPROP 1 LAST HDL_TAP TRUE
J 2
(575 3275);
DISPLAY 1.234043 (575 3275);
PAINT GREEN (575 3275);
DISPLAY INVISIBLE (575 3275);
FORCEPROP 1 LAST PATH I40
J 2
(900 3400);
DISPLAY 0.936170 (900 3400);
PAINT GREEN (900 3400);
DISPLAY INVISIBLE (900 3400);
FORCEADD TAP..6
R 2
(700 3450);
FORCEPROP 3 LASTPIN (650 3450) SIG_NAME M_B_DQS_DP<0>
J 0
(660 3460);
DISPLAY 0.659574 (660 3460);
PAINT MONO (660 3460);
DISPLAY INVISIBLE (660 3460);
FORCEPROP 1 LASTPIN (650 3450) BN 0
J 2
(700 3460);
DISPLAY 0.617021 (700 3460);
PAINT PINK (700 3460);
FORCEPROP 2 LAST CDS_LIB mstr_standard
J 0
(700 3450);
DISPLAY 0.787234 (700 3450);
PAINT MONO (700 3450);
DISPLAY INVISIBLE (700 3450);
FORCEPROP 1 LAST BODY_TYPE PLUMBING
J 2
(700 3400);
DISPLAY 1.234043 (700 3400);
PAINT GREEN (700 3400);
DISPLAY INVISIBLE (700 3400);
FORCEPROP 1 LAST HDL_TAP TRUE
J 2
(375 3325);
DISPLAY 1.234043 (375 3325);
PAINT GREEN (375 3325);
DISPLAY INVISIBLE (375 3325);
FORCEPROP 1 LAST PATH I41
J 2
(700 3450);
DISPLAY 0.936170 (700 3450);
PAINT GREEN (700 3450);
DISPLAY INVISIBLE (700 3450);
FORCEADD GND..1
R 2
(2500 1300);
FORCEPROP 3 LASTPIN (2500 1350) SIG_NAME GND\g
J 0
(2510 1360);
DISPLAY 0.659574 (2510 1360);
PAINT MONO (2510 1360);
DISPLAY INVISIBLE (2510 1360);
FORCEPROP 1 LAST VOLTAGE 0
J 0
(2500 1300);
PAINT SKYBLUE (2500 1300);
DISPLAY INVISIBLE (2500 1300);
FORCEPROP 2 LAST BOM_COST MEM
J 0
(2500 1305);
PAINT ORANGE (2500 1305);
DISPLAY INVISIBLE (2500 1305);
FORCEPROP 2 LAST CDS_LIB mstr_symbols
J 0
(2500 1300);
DISPLAY 0.787234 (2500 1300);
PAINT MONO (2500 1300);
DISPLAY INVISIBLE (2500 1300);
FORCEPROP 1 LAST SIZE 1B
J 2
(2425 1250);
DISPLAY 1.170213 (2425 1250);
PAINT GREEN (2425 1250);
DISPLAY INVISIBLE (2425 1250);
FORCEPROP 1 LAST BODY_TYPE PLUMBING
J 2
(2545 1257);
DISPLAY 0.340426 (2545 1257);
PAINT GREEN (2545 1257);
DISPLAY INVISIBLE (2545 1257);
FORCEPROP 1 LAST PATH I42
J 2
(2425 1300);
DISPLAY 0.936170 (2425 1300);
PAINT GREEN (2425 1300);
DISPLAY INVISIBLE (2425 1300);
FORCEPROP 2 LAST ROOM DDR4_CH_A
J 0
(2500 1305);
PAINT ORANGE (2500 1305);
DISPLAY INVISIBLE (2500 1305);
FORCEPROP 1 LAST HDL_POWER GND
J 2
(2500 1450);
DISPLAY 0.553191 (2500 1450);
PAINT GREEN (2500 1450);
DISPLAY INVISIBLE (2500 1450);
FORCEADD SCONN288_H44441004..3
(1800 2600);
FORCEPROP 1 LAST LOCATION J4G2
J 0
(1350 4000);
DISPLAY 0.617021 (1350 4000);
PAINT AQUA (1350 4000);
FORCEPROP 1 LAST PART_NUMBER H44441-004
J 0
(1350 1250);
DISPLAY 0.617021 (1350 1250);
PAINT BLUE (1350 1250);
FORCEPROP 1 LAST MATERIAL SCONN
J 0
(1350 3950);
DISPLAY 0.617021 (1350 3950);
PAINT SKYBLUE (1350 3950);
FORCEPROP 2 LASTPIN (1300 3750) $PN 2
J 2
(1290 3760);
DISPLAY 0.617021 (1290 3760);
PAINT ORANGE (1290 3760);
FORCEPROP 2 LASTPIN (1300 3700) $PN 4
J 2
(1290 3710);
DISPLAY 0.617021 (1290 3710);
PAINT ORANGE (1290 3710);
FORCEPROP 2 LASTPIN (1300 3650) $PN 6
J 2
(1290 3660);
DISPLAY 0.617021 (1290 3660);
PAINT ORANGE (1290 3660);
FORCEPROP 2 LASTPIN (1300 3600) $PN 9
J 2
(1290 3610);
DISPLAY 0.617021 (1290 3610);
PAINT ORANGE (1290 3610);
FORCEPROP 2 LASTPIN (1300 3550) $PN 11
J 2
(1290 3560);
DISPLAY 0.617021 (1290 3560);
PAINT ORANGE (1290 3560);
FORCEPROP 2 LASTPIN (1300 3500) $PN 13
J 2
(1290 3510);
DISPLAY 0.617021 (1290 3510);
PAINT ORANGE (1290 3510);
FORCEPROP 2 LASTPIN (1300 3450) $PN 15
J 2
(1290 3460);
DISPLAY 0.617021 (1290 3460);
PAINT ORANGE (1290 3460);
FORCEPROP 2 LASTPIN (1300 3400) $PN 17
J 2
(1290 3410);
DISPLAY 0.617021 (1290 3410);
PAINT ORANGE (1290 3410);
FORCEPROP 2 LASTPIN (1300 3350) $PN 20
J 2
(1290 3360);
DISPLAY 0.617021 (1290 3360);
PAINT ORANGE (1290 3360);
FORCEPROP 2 LASTPIN (1300 3300) $PN 22
J 2
(1290 3310);
DISPLAY 0.617021 (1290 3310);
PAINT ORANGE (1290 3310);
FORCEPROP 2 LASTPIN (1300 3250) $PN 24
J 2
(1290 3260);
DISPLAY 0.617021 (1290 3260);
PAINT ORANGE (1290 3260);
FORCEPROP 2 LASTPIN (1300 3200) $PN 26
J 2
(1290 3210);
DISPLAY 0.617021 (1290 3210);
PAINT ORANGE (1290 3210);
FORCEPROP 2 LASTPIN (1300 3150) $PN 28
J 2
(1290 3160);
DISPLAY 0.617021 (1290 3160);
PAINT ORANGE (1290 3160);
FORCEPROP 2 LASTPIN (1300 3100) $PN 31
J 2
(1290 3110);
DISPLAY 0.617021 (1290 3110);
PAINT ORANGE (1290 3110);
FORCEPROP 2 LASTPIN (1300 3050) $PN 33
J 2
(1290 3060);
DISPLAY 0.617021 (1290 3060);
PAINT ORANGE (1290 3060);
FORCEPROP 2 LASTPIN (1300 3000) $PN 35
J 2
(1290 3010);
DISPLAY 0.617021 (1290 3010);
PAINT ORANGE (1290 3010);
FORCEPROP 2 LASTPIN (1300 2950) $PN 37
J 2
(1290 2960);
DISPLAY 0.617021 (1290 2960);
PAINT ORANGE (1290 2960);
FORCEPROP 2 LASTPIN (1300 2900) $PN 39
J 2
(1290 2910);
DISPLAY 0.617021 (1290 2910);
PAINT ORANGE (1290 2910);
FORCEPROP 2 LASTPIN (1300 2850) $PN 42
J 2
(1290 2860);
DISPLAY 0.617021 (1290 2860);
PAINT ORANGE (1290 2860);
FORCEPROP 2 LASTPIN (1300 2800) $PN 44
J 2
(1290 2810);
DISPLAY 0.617021 (1290 2810);
PAINT ORANGE (1290 2810);
FORCEPROP 2 LASTPIN (1300 2750) $PN 46
J 2
(1290 2760);
DISPLAY 0.617021 (1290 2760);
PAINT ORANGE (1290 2760);
FORCEPROP 2 LASTPIN (1300 2700) $PN 48
J 2
(1290 2710);
DISPLAY 0.617021 (1290 2710);
PAINT ORANGE (1290 2710);
FORCEPROP 2 LASTPIN (1300 2650) $PN 50
J 2
(1290 2660);
DISPLAY 0.617021 (1290 2660);
PAINT ORANGE (1290 2660);
FORCEPROP 2 LASTPIN (1300 2600) $PN 53
J 2
(1290 2610);
DISPLAY 0.617021 (1290 2610);
PAINT ORANGE (1290 2610);
FORCEPROP 2 LASTPIN (1300 2550) $PN 55
J 2
(1290 2560);
DISPLAY 0.617021 (1290 2560);
PAINT ORANGE (1290 2560);
FORCEPROP 2 LASTPIN (1300 2500) $PN 57
J 2
(1290 2510);
DISPLAY 0.617021 (1290 2510);
PAINT ORANGE (1290 2510);
FORCEPROP 2 LASTPIN (1300 2450) $PN 94
J 2
(1290 2460);
DISPLAY 0.617021 (1290 2460);
PAINT ORANGE (1290 2460);
FORCEPROP 2 LASTPIN (1300 2400) $PN 96
J 2
(1290 2410);
DISPLAY 0.617021 (1290 2410);
PAINT ORANGE (1290 2410);
FORCEPROP 2 LASTPIN (1300 2350) $PN 98
J 2
(1290 2360);
DISPLAY 0.617021 (1290 2360);
PAINT ORANGE (1290 2360);
FORCEPROP 2 LASTPIN (1300 2300) $PN 101
J 2
(1290 2310);
DISPLAY 0.617021 (1290 2310);
PAINT ORANGE (1290 2310);
FORCEPROP 2 LASTPIN (1300 2250) $PN 103
J 2
(1290 2260);
DISPLAY 0.617021 (1290 2260);
PAINT ORANGE (1290 2260);
FORCEPROP 2 LASTPIN (1300 2200) $PN 105
J 2
(1290 2210);
DISPLAY 0.617021 (1290 2210);
PAINT ORANGE (1290 2210);
FORCEPROP 2 LASTPIN (1300 2150) $PN 107
J 2
(1290 2160);
DISPLAY 0.617021 (1290 2160);
PAINT ORANGE (1290 2160);
FORCEPROP 2 LASTPIN (1300 2100) $PN 109
J 2
(1290 2110);
DISPLAY 0.617021 (1290 2110);
PAINT ORANGE (1290 2110);
FORCEPROP 2 LASTPIN (1300 2050) $PN 112
J 2
(1290 2060);
DISPLAY 0.617021 (1290 2060);
PAINT ORANGE (1290 2060);
FORCEPROP 2 LASTPIN (1300 2000) $PN 114
J 2
(1290 2010);
DISPLAY 0.617021 (1290 2010);
PAINT ORANGE (1290 2010);
FORCEPROP 2 LASTPIN (1300 1950) $PN 116
J 2
(1290 1960);
DISPLAY 0.617021 (1290 1960);
PAINT ORANGE (1290 1960);
FORCEPROP 2 LASTPIN (1300 1900) $PN 118
J 2
(1290 1910);
DISPLAY 0.617021 (1290 1910);
PAINT ORANGE (1290 1910);
FORCEPROP 2 LASTPIN (1300 1850) $PN 120
J 2
(1290 1860);
DISPLAY 0.617021 (1290 1860);
PAINT ORANGE (1290 1860);
FORCEPROP 2 LASTPIN (1300 1800) $PN 123
J 2
(1290 1810);
DISPLAY 0.617021 (1290 1810);
PAINT ORANGE (1290 1810);
FORCEPROP 2 LASTPIN (1300 1750) $PN 125
J 2
(1290 1760);
DISPLAY 0.617021 (1290 1760);
PAINT ORANGE (1290 1760);
FORCEPROP 2 LASTPIN (1300 1700) $PN 127
J 2
(1290 1710);
DISPLAY 0.617021 (1290 1710);
PAINT ORANGE (1290 1710);
FORCEPROP 2 LASTPIN (1300 1650) $PN 129
J 2
(1290 1660);
DISPLAY 0.617021 (1290 1660);
PAINT ORANGE (1290 1660);
FORCEPROP 2 LASTPIN (1300 1600) $PN 131
J 2
(1290 1610);
DISPLAY 0.617021 (1290 1610);
PAINT ORANGE (1290 1610);
FORCEPROP 2 LASTPIN (1300 1550) $PN 134
J 2
(1290 1560);
DISPLAY 0.617021 (1290 1560);
PAINT ORANGE (1290 1560);
FORCEPROP 2 LASTPIN (1300 1500) $PN 136
J 2
(1290 1510);
DISPLAY 0.617021 (1290 1510);
PAINT ORANGE (1290 1510);
FORCEPROP 2 LASTPIN (1300 1450) $PN 138
J 2
(1290 1460);
DISPLAY 0.617021 (1290 1460);
PAINT ORANGE (1290 1460);
FORCEPROP 2 LASTPIN (2300 3750) $PN 147
J 0
(2310 3760);
DISPLAY 0.617021 (2310 3760);
PAINT ORANGE (2310 3760);
FORCEPROP 2 LASTPIN (2300 3700) $PN 149
J 0
(2310 3710);
DISPLAY 0.617021 (2310 3710);
PAINT ORANGE (2310 3710);
FORCEPROP 2 LASTPIN (2300 3650) $PN 151
J 0
(2310 3660);
DISPLAY 0.617021 (2310 3660);
PAINT ORANGE (2310 3660);
FORCEPROP 2 LASTPIN (2300 3600) $PN 154
J 0
(2310 3610);
DISPLAY 0.617021 (2310 3610);
PAINT ORANGE (2310 3610);
FORCEPROP 2 LASTPIN (2300 3550) $PN 156
J 0
(2310 3560);
DISPLAY 0.617021 (2310 3560);
PAINT ORANGE (2310 3560);
FORCEPROP 2 LASTPIN (2300 3500) $PN 158
J 0
(2310 3510);
DISPLAY 0.617021 (2310 3510);
PAINT ORANGE (2310 3510);
FORCEPROP 2 LASTPIN (2300 3450) $PN 160
J 0
(2310 3460);
DISPLAY 0.617021 (2310 3460);
PAINT ORANGE (2310 3460);
FORCEPROP 2 LASTPIN (2300 3400) $PN 162
J 0
(2310 3410);
DISPLAY 0.617021 (2310 3410);
PAINT ORANGE (2310 3410);
FORCEPROP 2 LASTPIN (2300 3350) $PN 165
J 0
(2310 3360);
DISPLAY 0.617021 (2310 3360);
PAINT ORANGE (2310 3360);
FORCEPROP 2 LASTPIN (2300 3300) $PN 167
J 0
(2310 3310);
DISPLAY 0.617021 (2310 3310);
PAINT ORANGE (2310 3310);
FORCEPROP 2 LASTPIN (2300 3250) $PN 169
J 0
(2310 3260);
DISPLAY 0.617021 (2310 3260);
PAINT ORANGE (2310 3260);
FORCEPROP 2 LASTPIN (2300 3200) $PN 171
J 0
(2310 3210);
DISPLAY 0.617021 (2310 3210);
PAINT ORANGE (2310 3210);
FORCEPROP 2 LASTPIN (2300 3150) $PN 173
J 0
(2310 3160);
DISPLAY 0.617021 (2310 3160);
PAINT ORANGE (2310 3160);
FORCEPROP 2 LASTPIN (2300 3100) $PN 176
J 0
(2310 3110);
DISPLAY 0.617021 (2310 3110);
PAINT ORANGE (2310 3110);
FORCEPROP 2 LASTPIN (2300 3050) $PN 178
J 0
(2310 3060);
DISPLAY 0.617021 (2310 3060);
PAINT ORANGE (2310 3060);
FORCEPROP 2 LASTPIN (2300 3000) $PN 180
J 0
(2310 3010);
DISPLAY 0.617021 (2310 3010);
PAINT ORANGE (2310 3010);
FORCEPROP 2 LASTPIN (2300 2950) $PN 182
J 0
(2310 2960);
DISPLAY 0.617021 (2310 2960);
PAINT ORANGE (2310 2960);
FORCEPROP 2 LASTPIN (2300 2900) $PN 184
J 0
(2310 2910);
DISPLAY 0.617021 (2310 2910);
PAINT ORANGE (2310 2910);
FORCEPROP 2 LASTPIN (2300 2850) $PN 187
J 0
(2310 2860);
DISPLAY 0.617021 (2310 2860);
PAINT ORANGE (2310 2860);
FORCEPROP 2 LASTPIN (2300 2800) $PN 189
J 0
(2310 2810);
DISPLAY 0.617021 (2310 2810);
PAINT ORANGE (2310 2810);
FORCEPROP 2 LASTPIN (2300 2750) $PN 191
J 0
(2310 2760);
DISPLAY 0.617021 (2310 2760);
PAINT ORANGE (2310 2760);
FORCEPROP 2 LASTPIN (2300 2700) $PN 193
J 0
(2310 2710);
DISPLAY 0.617021 (2310 2710);
PAINT ORANGE (2310 2710);
FORCEPROP 2 LASTPIN (2300 2650) $PN 195
J 0
(2310 2660);
DISPLAY 0.617021 (2310 2660);
PAINT ORANGE (2310 2660);
FORCEPROP 2 LASTPIN (2300 2600) $PN 198
J 0
(2310 2610);
DISPLAY 0.617021 (2310 2610);
PAINT ORANGE (2310 2610);
FORCEPROP 2 LASTPIN (2300 2550) $PN 200
J 0
(2310 2560);
DISPLAY 0.617021 (2310 2560);
PAINT ORANGE (2310 2560);
FORCEPROP 2 LASTPIN (2300 2500) $PN 202
J 0
(2310 2510);
DISPLAY 0.617021 (2310 2510);
PAINT ORANGE (2310 2510);
FORCEPROP 2 LASTPIN (2300 2450) $PN 239
J 0
(2310 2460);
DISPLAY 0.617021 (2310 2460);
PAINT ORANGE (2310 2460);
FORCEPROP 2 LASTPIN (2300 2400) $PN 241
J 0
(2310 2410);
DISPLAY 0.617021 (2310 2410);
PAINT ORANGE (2310 2410);
FORCEPROP 2 LASTPIN (2300 2350) $PN 243
J 0
(2310 2360);
DISPLAY 0.617021 (2310 2360);
PAINT ORANGE (2310 2360);
FORCEPROP 2 LASTPIN (2300 2300) $PN 246
J 0
(2310 2310);
DISPLAY 0.617021 (2310 2310);
PAINT ORANGE (2310 2310);
FORCEPROP 2 LASTPIN (2300 2250) $PN 248
J 0
(2310 2260);
DISPLAY 0.617021 (2310 2260);
PAINT ORANGE (2310 2260);
FORCEPROP 2 LASTPIN (2300 2200) $PN 250
J 0
(2310 2210);
DISPLAY 0.617021 (2310 2210);
PAINT ORANGE (2310 2210);
FORCEPROP 2 LASTPIN (2300 2150) $PN 252
J 0
(2310 2160);
DISPLAY 0.617021 (2310 2160);
PAINT ORANGE (2310 2160);
FORCEPROP 2 LASTPIN (2300 2100) $PN 254
J 0
(2310 2110);
DISPLAY 0.617021 (2310 2110);
PAINT ORANGE (2310 2110);
FORCEPROP 2 LASTPIN (2300 2050) $PN 257
J 0
(2310 2060);
DISPLAY 0.617021 (2310 2060);
PAINT ORANGE (2310 2060);
FORCEPROP 2 LASTPIN (2300 2000) $PN 259
J 0
(2310 2010);
DISPLAY 0.617021 (2310 2010);
PAINT ORANGE (2310 2010);
FORCEPROP 2 LASTPIN (2300 1950) $PN 261
J 0
(2310 1960);
DISPLAY 0.617021 (2310 1960);
PAINT ORANGE (2310 1960);
FORCEPROP 2 LASTPIN (2300 1900) $PN 263
J 0
(2310 1910);
DISPLAY 0.617021 (2310 1910);
PAINT ORANGE (2310 1910);
FORCEPROP 2 LASTPIN (2300 1850) $PN 265
J 0
(2310 1860);
DISPLAY 0.617021 (2310 1860);
PAINT ORANGE (2310 1860);
FORCEPROP 2 LASTPIN (2300 1800) $PN 268
J 0
(2310 1810);
DISPLAY 0.617021 (2310 1810);
PAINT ORANGE (2310 1810);
FORCEPROP 2 LASTPIN (2300 1750) $PN 270
J 0
(2310 1760);
DISPLAY 0.617021 (2310 1760);
PAINT ORANGE (2310 1760);
FORCEPROP 2 LASTPIN (2300 1700) $PN 272
J 0
(2310 1710);
DISPLAY 0.617021 (2310 1710);
PAINT ORANGE (2310 1710);
FORCEPROP 2 LASTPIN (2300 1650) $PN 274
J 0
(2310 1660);
DISPLAY 0.617021 (2310 1660);
PAINT ORANGE (2310 1660);
FORCEPROP 2 LASTPIN (2300 1600) $PN 276
J 0
(2310 1610);
DISPLAY 0.617021 (2310 1610);
PAINT ORANGE (2310 1610);
FORCEPROP 2 LASTPIN (2300 1550) $PN 279
J 0
(2310 1560);
DISPLAY 0.617021 (2310 1560);
PAINT ORANGE (2310 1560);
FORCEPROP 2 LASTPIN (2300 1500) $PN 281
J 0
(2310 1510);
DISPLAY 0.617021 (2310 1510);
PAINT ORANGE (2310 1510);
FORCEPROP 2 LASTPIN (2300 1450) $PN 283
J 0
(2310 1460);
DISPLAY 0.617021 (2310 1460);
PAINT ORANGE (2310 1460);
FORCEPROP 1 LAST PACK_TYPE PIP
J 0
(1350 4050);
PAINT SKYBLUE (1350 4050);
DISPLAY INVISIBLE (1350 4050);
FORCEPROP 2 LAST BOM_COST MEM
J 0
(1800 2600);
PAINT ORANGE (1800 2600);
DISPLAY INVISIBLE (1800 2600);
FORCEPROP 2 LAST CDS_LIB mstr_sconn
J 0
(1800 2600);
PAINT ORANGE (1800 2600);
DISPLAY INVISIBLE (1800 2600);
FORCEPROP 2 LAST SEC_TYPE PIP
J 0
(1350 4050);
DISPLAY 1.021277 (1350 4050);
PAINT ORANGE (1350 4050);
DISPLAY INVISIBLE (1350 4050);
FORCEPROP 2 LAST SEC 3
J 0
(1350 4050);
DISPLAY 0.680851 (1350 4050);
PAINT MONO (1350 4050);
DISPLAY INVISIBLE (1350 4050);
FORCEPROP 2 LAST CDS_LOCATION J4G2
J 0
(1350 4000);
DISPLAY 0.617021 (1350 4000);
PAINT AQUA (1350 4000);
DISPLAY INVISIBLE (1350 4000);
FORCEPROP 1 LAST PATH I43
J 0
(1800 3950);
PAINT GREEN (1800 3950);
DISPLAY INVISIBLE (1800 3950);
FORCEPROP 2 LAST ROOM DDR4_CH_B
J 0
(1800 2600);
PAINT ORANGE (1800 2600);
DISPLAY INVISIBLE (1800 2600);
FORCEADD GND..1
R 2
(1100 1300);
FORCEPROP 3 LASTPIN (1100 1350) SIG_NAME GND\g
J 0
(1110 1360);
DISPLAY 0.659574 (1110 1360);
PAINT MONO (1110 1360);
DISPLAY INVISIBLE (1110 1360);
FORCEPROP 1 LAST VOLTAGE 0
J 0
(1100 1300);
PAINT SKYBLUE (1100 1300);
DISPLAY INVISIBLE (1100 1300);
FORCEPROP 2 LAST BOM_COST MEM
J 0
(1100 1305);
PAINT ORANGE (1100 1305);
DISPLAY INVISIBLE (1100 1305);
FORCEPROP 2 LAST CDS_LIB mstr_symbols
J 0
(1100 1300);
DISPLAY 0.787234 (1100 1300);
PAINT MONO (1100 1300);
DISPLAY INVISIBLE (1100 1300);
FORCEPROP 1 LAST SIZE 1B
J 2
(1025 1250);
DISPLAY 1.170213 (1025 1250);
PAINT GREEN (1025 1250);
DISPLAY INVISIBLE (1025 1250);
FORCEPROP 1 LAST BODY_TYPE PLUMBING
J 2
(1145 1257);
DISPLAY 0.340426 (1145 1257);
PAINT GREEN (1145 1257);
DISPLAY INVISIBLE (1145 1257);
FORCEPROP 1 LAST PATH I44
J 2
(1025 1300);
DISPLAY 0.936170 (1025 1300);
PAINT GREEN (1025 1300);
DISPLAY INVISIBLE (1025 1300);
FORCEPROP 2 LAST ROOM DDR4_CH_A
J 0
(1100 1305);
PAINT ORANGE (1100 1305);
DISPLAY INVISIBLE (1100 1305);
FORCEPROP 1 LAST HDL_POWER GND
J 2
(1100 1450);
DISPLAY 0.553191 (1100 1450);
PAINT GREEN (1100 1450);
DISPLAY INVISIBLE (1100 1450);
FORCEADD OFFPAGE..3
(-1150 4650);
FORCEPROP 2 LAST $XR0 24 
J 0
(-936 4650);
DISPLAY 0.638298 (-936 4650);
PAINT MONO (-936 4650);
FORCEPROP 2 LAST $XR1 46 
J 0
(-846 4650);
DISPLAY 0.638298 (-846 4650);
PAINT MONO (-846 4650);
FORCEPROP 2 LAST CDS_LIB mstr_standard
J 0
(-1150 4650);
DISPLAY 0.787234 (-1150 4650);
PAINT MONO (-1150 4650);
DISPLAY INVISIBLE (-1150 4650);
FORCEPROP 1 LAST OFFPAGE TRUE
J 0
(-825 4525);
DISPLAY 0.936170 (-825 4525);
PAINT GREEN (-825 4525);
DISPLAY INVISIBLE (-825 4525);
FORCEPROP 1 LAST COMMENT_BODY TRUE
J 0
(-1200 4550);
DISPLAY 0.936170 (-1200 4550);
PAINT GREEN (-1200 4550);
DISPLAY INVISIBLE (-1200 4550);
FORCEPROP 2 LAST PATH I45
J 0
(-950 4725);
DISPLAY 0.787234 (-950 4725);
PAINT MONO (-950 4725);
DISPLAY INVISIBLE (-950 4725);
FORCEADD TAP..6
R 2
(-1700 4600);
FORCEPROP 3 LASTPIN (-1750 4600) SIG_NAME M_B_DQ<62>
J 0
(-1740 4610);
DISPLAY 0.659574 (-1740 4610);
PAINT MONO (-1740 4610);
DISPLAY INVISIBLE (-1740 4610);
FORCEPROP 1 LASTPIN (-1750 4600) BN 62
J 2
(-1700 4610);
DISPLAY 0.617021 (-1700 4610);
PAINT PINK (-1700 4610);
FORCEPROP 2 LAST CDS_LIB mstr_standard
J 2
(-1700 4600);
DISPLAY 0.787234 (-1700 4600);
PAINT MONO (-1700 4600);
DISPLAY INVISIBLE (-1700 4600);
FORCEPROP 1 LAST BODY_TYPE PLUMBING
J 2
(-1700 4550);
DISPLAY 1.234043 (-1700 4550);
PAINT GREEN (-1700 4550);
DISPLAY INVISIBLE (-1700 4550);
FORCEPROP 1 LAST HDL_TAP TRUE
J 2
(-2025 4475);
DISPLAY 1.234043 (-2025 4475);
PAINT GREEN (-2025 4475);
DISPLAY INVISIBLE (-2025 4475);
FORCEPROP 1 LAST PATH I46
J 2
(-1700 4600);
DISPLAY 0.936170 (-1700 4600);
PAINT GREEN (-1700 4600);
DISPLAY INVISIBLE (-1700 4600);
FORCEADD TAP..6
R 2
(-1700 4550);
FORCEPROP 3 LASTPIN (-1750 4550) SIG_NAME M_B_DQ<63>
J 0
(-1740 4560);
DISPLAY 0.659574 (-1740 4560);
PAINT MONO (-1740 4560);
DISPLAY INVISIBLE (-1740 4560);
FORCEPROP 1 LASTPIN (-1750 4550) BN 63
J 2
(-1700 4560);
DISPLAY 0.617021 (-1700 4560);
PAINT PINK (-1700 4560);
FORCEPROP 2 LAST CDS_LIB mstr_standard
J 2
(-1700 4550);
DISPLAY 0.787234 (-1700 4550);
PAINT MONO (-1700 4550);
DISPLAY INVISIBLE (-1700 4550);
FORCEPROP 1 LAST BODY_TYPE PLUMBING
J 2
(-1700 4500);
DISPLAY 1.234043 (-1700 4500);
PAINT GREEN (-1700 4500);
DISPLAY INVISIBLE (-1700 4500);
FORCEPROP 1 LAST HDL_TAP TRUE
J 2
(-2025 4425);
DISPLAY 1.234043 (-2025 4425);
PAINT GREEN (-2025 4425);
DISPLAY INVISIBLE (-2025 4425);
FORCEPROP 1 LAST PATH I47
J 2
(-1700 4550);
DISPLAY 0.936170 (-1700 4550);
PAINT GREEN (-1700 4550);
DISPLAY INVISIBLE (-1700 4550);
FORCEADD TAP..6
R 2
(-1700 4400);
FORCEPROP 3 LASTPIN (-1750 4400) SIG_NAME M_B_DQ<58>
J 0
(-1740 4410);
DISPLAY 0.659574 (-1740 4410);
PAINT MONO (-1740 4410);
DISPLAY INVISIBLE (-1740 4410);
FORCEPROP 1 LASTPIN (-1750 4400) BN 58
J 2
(-1700 4410);
DISPLAY 0.617021 (-1700 4410);
PAINT PINK (-1700 4410);
FORCEPROP 2 LAST CDS_LIB mstr_standard
J 2
(-1700 4400);
DISPLAY 0.787234 (-1700 4400);
PAINT MONO (-1700 4400);
DISPLAY INVISIBLE (-1700 4400);
FORCEPROP 1 LAST BODY_TYPE PLUMBING
J 2
(-1700 4350);
DISPLAY 1.234043 (-1700 4350);
PAINT GREEN (-1700 4350);
DISPLAY INVISIBLE (-1700 4350);
FORCEPROP 1 LAST HDL_TAP TRUE
J 2
(-2025 4275);
DISPLAY 1.234043 (-2025 4275);
PAINT GREEN (-2025 4275);
DISPLAY INVISIBLE (-2025 4275);
FORCEPROP 1 LAST PATH I48
J 2
(-1700 4400);
DISPLAY 0.936170 (-1700 4400);
PAINT GREEN (-1700 4400);
DISPLAY INVISIBLE (-1700 4400);
FORCEADD TAP..6
R 2
(-1700 4450);
FORCEPROP 3 LASTPIN (-1750 4450) SIG_NAME M_B_DQ<61>
J 0
(-1740 4460);
DISPLAY 0.659574 (-1740 4460);
PAINT MONO (-1740 4460);
DISPLAY INVISIBLE (-1740 4460);
FORCEPROP 1 LASTPIN (-1750 4450) BN 61
J 2
(-1700 4460);
DISPLAY 0.617021 (-1700 4460);
PAINT PINK (-1700 4460);
FORCEPROP 2 LAST CDS_LIB mstr_standard
J 2
(-1700 4450);
DISPLAY 0.787234 (-1700 4450);
PAINT MONO (-1700 4450);
DISPLAY INVISIBLE (-1700 4450);
FORCEPROP 1 LAST BODY_TYPE PLUMBING
J 2
(-1700 4400);
DISPLAY 1.234043 (-1700 4400);
PAINT GREEN (-1700 4400);
DISPLAY INVISIBLE (-1700 4400);
FORCEPROP 1 LAST HDL_TAP TRUE
J 2
(-2025 4325);
DISPLAY 1.234043 (-2025 4325);
PAINT GREEN (-2025 4325);
DISPLAY INVISIBLE (-2025 4325);
FORCEPROP 1 LAST PATH I49
J 2
(-1700 4450);
DISPLAY 0.936170 (-1700 4450);
PAINT GREEN (-1700 4450);
DISPLAY INVISIBLE (-1700 4450);
FORCEADD TAP..6
R 2
(700 5050);
FORCEPROP 3 LASTPIN (650 5050) SIG_NAME M_B_DQS_DP<16>
J 0
(660 5060);
DISPLAY 0.659574 (660 5060);
PAINT MONO (660 5060);
DISPLAY INVISIBLE (660 5060);
FORCEPROP 1 LASTPIN (650 5050) BN 16
J 2
(700 5060);
DISPLAY 0.617021 (700 5060);
PAINT PINK (700 5060);
FORCEPROP 2 LAST CDS_LIB mstr_standard
J 0
(700 5050);
DISPLAY 0.787234 (700 5050);
PAINT MONO (700 5050);
DISPLAY INVISIBLE (700 5050);
FORCEPROP 1 LAST BODY_TYPE PLUMBING
J 2
(700 5000);
DISPLAY 1.234043 (700 5000);
PAINT GREEN (700 5000);
DISPLAY INVISIBLE (700 5000);
FORCEPROP 1 LAST HDL_TAP TRUE
J 2
(375 4925);
DISPLAY 1.234043 (375 4925);
PAINT GREEN (375 4925);
DISPLAY INVISIBLE (375 4925);
FORCEPROP 1 LAST PATH I5
J 2
(700 5050);
DISPLAY 0.936170 (700 5050);
PAINT GREEN (700 5050);
DISPLAY INVISIBLE (700 5050);
FORCEADD TAP..6
R 2
(-1700 4500);
FORCEPROP 3 LASTPIN (-1750 4500) SIG_NAME M_B_DQ<60>
J 0
(-1740 4510);
DISPLAY 0.659574 (-1740 4510);
PAINT MONO (-1740 4510);
DISPLAY INVISIBLE (-1740 4510);
FORCEPROP 1 LASTPIN (-1750 4500) BN 60
J 2
(-1700 4510);
DISPLAY 0.617021 (-1700 4510);
PAINT PINK (-1700 4510);
FORCEPROP 2 LAST CDS_LIB mstr_standard
J 2
(-1700 4500);
DISPLAY 0.787234 (-1700 4500);
PAINT MONO (-1700 4500);
DISPLAY INVISIBLE (-1700 4500);
FORCEPROP 1 LAST BODY_TYPE PLUMBING
J 2
(-1700 4450);
DISPLAY 1.234043 (-1700 4450);
PAINT GREEN (-1700 4450);
DISPLAY INVISIBLE (-1700 4450);
FORCEPROP 1 LAST HDL_TAP TRUE
J 2
(-2025 4375);
DISPLAY 1.234043 (-2025 4375);
PAINT GREEN (-2025 4375);
DISPLAY INVISIBLE (-2025 4375);
FORCEPROP 1 LAST PATH I50
J 2
(-1700 4500);
DISPLAY 0.936170 (-1700 4500);
PAINT GREEN (-1700 4500);
DISPLAY INVISIBLE (-1700 4500);
FORCEADD TAP..6
R 2
(-1700 4300);
FORCEPROP 3 LASTPIN (-1750 4300) SIG_NAME M_B_DQ<56>
J 0
(-1740 4310);
DISPLAY 0.659574 (-1740 4310);
PAINT MONO (-1740 4310);
DISPLAY INVISIBLE (-1740 4310);
FORCEPROP 1 LASTPIN (-1750 4300) BN 56
J 2
(-1700 4310);
DISPLAY 0.617021 (-1700 4310);
PAINT PINK (-1700 4310);
FORCEPROP 2 LAST CDS_LIB mstr_standard
J 2
(-1700 4300);
DISPLAY 0.787234 (-1700 4300);
PAINT MONO (-1700 4300);
DISPLAY INVISIBLE (-1700 4300);
FORCEPROP 1 LAST BODY_TYPE PLUMBING
J 2
(-1700 4250);
DISPLAY 1.234043 (-1700 4250);
PAINT GREEN (-1700 4250);
DISPLAY INVISIBLE (-1700 4250);
FORCEPROP 1 LAST HDL_TAP TRUE
J 2
(-2025 4175);
DISPLAY 1.234043 (-2025 4175);
PAINT GREEN (-2025 4175);
DISPLAY INVISIBLE (-2025 4175);
FORCEPROP 1 LAST PATH I51
J 2
(-1700 4300);
DISPLAY 0.936170 (-1700 4300);
PAINT GREEN (-1700 4300);
DISPLAY INVISIBLE (-1700 4300);
FORCEADD TAP..6
R 2
(-1700 4350);
FORCEPROP 3 LASTPIN (-1750 4350) SIG_NAME M_B_DQ<59>
J 0
(-1740 4360);
DISPLAY 0.659574 (-1740 4360);
PAINT MONO (-1740 4360);
DISPLAY INVISIBLE (-1740 4360);
FORCEPROP 1 LASTPIN (-1750 4350) BN 59
J 2
(-1700 4360);
DISPLAY 0.617021 (-1700 4360);
PAINT PINK (-1700 4360);
FORCEPROP 2 LAST CDS_LIB mstr_standard
J 2
(-1700 4350);
DISPLAY 0.787234 (-1700 4350);
PAINT MONO (-1700 4350);
DISPLAY INVISIBLE (-1700 4350);
FORCEPROP 1 LAST BODY_TYPE PLUMBING
J 2
(-1700 4300);
DISPLAY 1.234043 (-1700 4300);
PAINT GREEN (-1700 4300);
DISPLAY INVISIBLE (-1700 4300);
FORCEPROP 1 LAST HDL_TAP TRUE
J 2
(-2025 4225);
DISPLAY 1.234043 (-2025 4225);
PAINT GREEN (-2025 4225);
DISPLAY INVISIBLE (-2025 4225);
FORCEPROP 1 LAST PATH I52
J 2
(-1700 4350);
DISPLAY 0.936170 (-1700 4350);
PAINT GREEN (-1700 4350);
DISPLAY INVISIBLE (-1700 4350);
FORCEADD TAP..6
R 2
(-1700 4150);
FORCEPROP 3 LASTPIN (-1750 4150) SIG_NAME M_B_DQ<55>
J 0
(-1740 4160);
DISPLAY 0.659574 (-1740 4160);
PAINT MONO (-1740 4160);
DISPLAY INVISIBLE (-1740 4160);
FORCEPROP 1 LASTPIN (-1750 4150) BN 55
J 2
(-1700 4160);
DISPLAY 0.617021 (-1700 4160);
PAINT PINK (-1700 4160);
FORCEPROP 2 LAST CDS_LIB mstr_standard
J 2
(-1700 4150);
DISPLAY 0.787234 (-1700 4150);
PAINT MONO (-1700 4150);
DISPLAY INVISIBLE (-1700 4150);
FORCEPROP 1 LAST BODY_TYPE PLUMBING
J 2
(-1700 4100);
DISPLAY 1.234043 (-1700 4100);
PAINT GREEN (-1700 4100);
DISPLAY INVISIBLE (-1700 4100);
FORCEPROP 1 LAST HDL_TAP TRUE
J 2
(-2025 4025);
DISPLAY 1.234043 (-2025 4025);
PAINT GREEN (-2025 4025);
DISPLAY INVISIBLE (-2025 4025);
FORCEPROP 1 LAST PATH I53
J 2
(-1700 4150);
DISPLAY 0.936170 (-1700 4150);
PAINT GREEN (-1700 4150);
DISPLAY INVISIBLE (-1700 4150);
FORCEADD TAP..6
R 2
(-1700 4200);
FORCEPROP 3 LASTPIN (-1750 4200) SIG_NAME M_B_DQ<54>
J 0
(-1740 4210);
DISPLAY 0.659574 (-1740 4210);
PAINT MONO (-1740 4210);
DISPLAY INVISIBLE (-1740 4210);
FORCEPROP 1 LASTPIN (-1750 4200) BN 54
J 2
(-1700 4210);
DISPLAY 0.617021 (-1700 4210);
PAINT PINK (-1700 4210);
FORCEPROP 2 LAST CDS_LIB mstr_standard
J 2
(-1700 4200);
DISPLAY 0.787234 (-1700 4200);
PAINT MONO (-1700 4200);
DISPLAY INVISIBLE (-1700 4200);
FORCEPROP 1 LAST BODY_TYPE PLUMBING
J 2
(-1700 4150);
DISPLAY 1.234043 (-1700 4150);
PAINT GREEN (-1700 4150);
DISPLAY INVISIBLE (-1700 4150);
FORCEPROP 1 LAST HDL_TAP TRUE
J 2
(-2025 4075);
DISPLAY 1.234043 (-2025 4075);
PAINT GREEN (-2025 4075);
DISPLAY INVISIBLE (-2025 4075);
FORCEPROP 1 LAST PATH I54
J 2
(-1700 4200);
DISPLAY 0.936170 (-1700 4200);
PAINT GREEN (-1700 4200);
DISPLAY INVISIBLE (-1700 4200);
FORCEADD TAP..6
R 2
(-1700 4250);
FORCEPROP 3 LASTPIN (-1750 4250) SIG_NAME M_B_DQ<57>
J 0
(-1740 4260);
DISPLAY 0.659574 (-1740 4260);
PAINT MONO (-1740 4260);
DISPLAY INVISIBLE (-1740 4260);
FORCEPROP 1 LASTPIN (-1750 4250) BN 57
J 2
(-1700 4260);
DISPLAY 0.617021 (-1700 4260);
PAINT PINK (-1700 4260);
FORCEPROP 2 LAST CDS_LIB mstr_standard
J 2
(-1700 4250);
DISPLAY 0.787234 (-1700 4250);
PAINT MONO (-1700 4250);
DISPLAY INVISIBLE (-1700 4250);
FORCEPROP 1 LAST BODY_TYPE PLUMBING
J 2
(-1700 4200);
DISPLAY 1.234043 (-1700 4200);
PAINT GREEN (-1700 4200);
DISPLAY INVISIBLE (-1700 4200);
FORCEPROP 1 LAST HDL_TAP TRUE
J 2
(-2025 4125);
DISPLAY 1.234043 (-2025 4125);
PAINT GREEN (-2025 4125);
DISPLAY INVISIBLE (-2025 4125);
FORCEPROP 1 LAST PATH I55
J 2
(-1700 4250);
DISPLAY 0.936170 (-1700 4250);
PAINT GREEN (-1700 4250);
DISPLAY INVISIBLE (-1700 4250);
FORCEADD TAP..6
R 2
(-1700 4050);
FORCEPROP 3 LASTPIN (-1750 4050) SIG_NAME M_B_DQ<53>
J 0
(-1740 4060);
DISPLAY 0.659574 (-1740 4060);
PAINT MONO (-1740 4060);
DISPLAY INVISIBLE (-1740 4060);
FORCEPROP 1 LASTPIN (-1750 4050) BN 53
J 2
(-1700 4060);
DISPLAY 0.617021 (-1700 4060);
PAINT PINK (-1700 4060);
FORCEPROP 2 LAST CDS_LIB mstr_standard
J 2
(-1700 4050);
DISPLAY 0.787234 (-1700 4050);
PAINT MONO (-1700 4050);
DISPLAY INVISIBLE (-1700 4050);
FORCEPROP 1 LAST BODY_TYPE PLUMBING
J 2
(-1700 4000);
DISPLAY 1.234043 (-1700 4000);
PAINT GREEN (-1700 4000);
DISPLAY INVISIBLE (-1700 4000);
FORCEPROP 1 LAST HDL_TAP TRUE
J 2
(-2025 3925);
DISPLAY 1.234043 (-2025 3925);
PAINT GREEN (-2025 3925);
DISPLAY INVISIBLE (-2025 3925);
FORCEPROP 1 LAST PATH I56
J 2
(-1700 4050);
DISPLAY 0.936170 (-1700 4050);
PAINT GREEN (-1700 4050);
DISPLAY INVISIBLE (-1700 4050);
FORCEADD TAP..6
R 2
(-1700 4100);
FORCEPROP 3 LASTPIN (-1750 4100) SIG_NAME M_B_DQ<52>
J 0
(-1740 4110);
DISPLAY 0.659574 (-1740 4110);
PAINT MONO (-1740 4110);
DISPLAY INVISIBLE (-1740 4110);
FORCEPROP 1 LASTPIN (-1750 4100) BN 52
J 2
(-1700 4110);
DISPLAY 0.617021 (-1700 4110);
PAINT PINK (-1700 4110);
FORCEPROP 2 LAST CDS_LIB mstr_standard
J 2
(-1700 4100);
DISPLAY 0.787234 (-1700 4100);
PAINT MONO (-1700 4100);
DISPLAY INVISIBLE (-1700 4100);
FORCEPROP 1 LAST BODY_TYPE PLUMBING
J 2
(-1700 4050);
DISPLAY 1.234043 (-1700 4050);
PAINT GREEN (-1700 4050);
DISPLAY INVISIBLE (-1700 4050);
FORCEPROP 1 LAST HDL_TAP TRUE
J 2
(-2025 3975);
DISPLAY 1.234043 (-2025 3975);
PAINT GREEN (-2025 3975);
DISPLAY INVISIBLE (-2025 3975);
FORCEPROP 1 LAST PATH I57
J 2
(-1700 4100);
DISPLAY 0.936170 (-1700 4100);
PAINT GREEN (-1700 4100);
DISPLAY INVISIBLE (-1700 4100);
FORCEADD TAP..6
R 2
(-1700 4000);
FORCEPROP 3 LASTPIN (-1750 4000) SIG_NAME M_B_DQ<50>
J 0
(-1740 4010);
DISPLAY 0.659574 (-1740 4010);
PAINT MONO (-1740 4010);
DISPLAY INVISIBLE (-1740 4010);
FORCEPROP 1 LASTPIN (-1750 4000) BN 50
J 2
(-1700 4010);
DISPLAY 0.617021 (-1700 4010);
PAINT PINK (-1700 4010);
FORCEPROP 2 LAST CDS_LIB mstr_standard
J 2
(-1700 4000);
DISPLAY 0.787234 (-1700 4000);
PAINT MONO (-1700 4000);
DISPLAY INVISIBLE (-1700 4000);
FORCEPROP 1 LAST BODY_TYPE PLUMBING
J 2
(-1700 3950);
DISPLAY 1.234043 (-1700 3950);
PAINT GREEN (-1700 3950);
DISPLAY INVISIBLE (-1700 3950);
FORCEPROP 1 LAST HDL_TAP TRUE
J 2
(-2025 3875);
DISPLAY 1.234043 (-2025 3875);
PAINT GREEN (-2025 3875);
DISPLAY INVISIBLE (-2025 3875);
FORCEPROP 1 LAST PATH I58
J 2
(-1700 4000);
DISPLAY 0.936170 (-1700 4000);
PAINT GREEN (-1700 4000);
DISPLAY INVISIBLE (-1700 4000);
FORCEADD TAP..6
R 2
(-1700 3950);
FORCEPROP 3 LASTPIN (-1750 3950) SIG_NAME M_B_DQ<51>
J 0
(-1740 3960);
DISPLAY 0.659574 (-1740 3960);
PAINT MONO (-1740 3960);
DISPLAY INVISIBLE (-1740 3960);
FORCEPROP 1 LASTPIN (-1750 3950) BN 51
J 2
(-1700 3960);
DISPLAY 0.617021 (-1700 3960);
PAINT PINK (-1700 3960);
FORCEPROP 2 LAST CDS_LIB mstr_standard
J 2
(-1700 3950);
DISPLAY 0.787234 (-1700 3950);
PAINT MONO (-1700 3950);
DISPLAY INVISIBLE (-1700 3950);
FORCEPROP 1 LAST BODY_TYPE PLUMBING
J 2
(-1700 3900);
DISPLAY 1.234043 (-1700 3900);
PAINT GREEN (-1700 3900);
DISPLAY INVISIBLE (-1700 3900);
FORCEPROP 1 LAST HDL_TAP TRUE
J 2
(-2025 3825);
DISPLAY 1.234043 (-2025 3825);
PAINT GREEN (-2025 3825);
DISPLAY INVISIBLE (-2025 3825);
FORCEPROP 1 LAST PATH I59
J 2
(-1700 3950);
DISPLAY 0.936170 (-1700 3950);
PAINT GREEN (-1700 3950);
DISPLAY INVISIBLE (-1700 3950);
FORCEADD TAP..6
R 2
(900 4900);
FORCEPROP 3 LASTPIN (850 4900) SIG_NAME M_B_DQS_DN<15>
J 0
(860 4910);
DISPLAY 0.659574 (860 4910);
PAINT MONO (860 4910);
DISPLAY INVISIBLE (860 4910);
FORCEPROP 1 LASTPIN (850 4900) BN 15
J 2
(900 4910);
DISPLAY 0.617021 (900 4910);
PAINT PINK (900 4910);
FORCEPROP 2 LAST CDS_LIB mstr_standard
J 0
(900 4900);
DISPLAY 0.787234 (900 4900);
PAINT MONO (900 4900);
DISPLAY INVISIBLE (900 4900);
FORCEPROP 1 LAST BODY_TYPE PLUMBING
J 2
(900 4850);
DISPLAY 1.234043 (900 4850);
PAINT GREEN (900 4850);
DISPLAY INVISIBLE (900 4850);
FORCEPROP 1 LAST HDL_TAP TRUE
J 2
(575 4775);
DISPLAY 1.234043 (575 4775);
PAINT GREEN (575 4775);
DISPLAY INVISIBLE (575 4775);
FORCEPROP 1 LAST PATH I6
J 2
(900 4900);
DISPLAY 0.936170 (900 4900);
PAINT GREEN (900 4900);
DISPLAY INVISIBLE (900 4900);
FORCEADD TAP..6
R 2
(-1700 3900);
FORCEPROP 3 LASTPIN (-1750 3900) SIG_NAME M_B_DQ<48>
J 0
(-1740 3910);
DISPLAY 0.659574 (-1740 3910);
PAINT MONO (-1740 3910);
DISPLAY INVISIBLE (-1740 3910);
FORCEPROP 1 LASTPIN (-1750 3900) BN 48
J 2
(-1700 3910);
DISPLAY 0.617021 (-1700 3910);
PAINT PINK (-1700 3910);
FORCEPROP 2 LAST CDS_LIB mstr_standard
J 2
(-1700 3900);
DISPLAY 0.787234 (-1700 3900);
PAINT MONO (-1700 3900);
DISPLAY INVISIBLE (-1700 3900);
FORCEPROP 1 LAST BODY_TYPE PLUMBING
J 2
(-1700 3850);
DISPLAY 1.234043 (-1700 3850);
PAINT GREEN (-1700 3850);
DISPLAY INVISIBLE (-1700 3850);
FORCEPROP 1 LAST HDL_TAP TRUE
J 2
(-2025 3775);
DISPLAY 1.234043 (-2025 3775);
PAINT GREEN (-2025 3775);
DISPLAY INVISIBLE (-2025 3775);
FORCEPROP 1 LAST PATH I60
J 2
(-1700 3900);
DISPLAY 0.936170 (-1700 3900);
PAINT GREEN (-1700 3900);
DISPLAY INVISIBLE (-1700 3900);
FORCEADD SCONN288_H44441004..2
(0 4300);
FORCEPROP 1 LAST LOCATION J4G2
J 0
(-400 5400);
DISPLAY 0.617021 (-400 5400);
PAINT AQUA (-400 5400);
FORCEPROP 1 LAST PART_NUMBER H44441-004
J 0
(-400 3200);
DISPLAY 0.617021 (-400 3200);
PAINT BLUE (-400 3200);
FORCEPROP 1 LAST MATERIAL SCONN
J 0
(-400 5350);
DISPLAY 0.617021 (-400 5350);
PAINT SKYBLUE (-400 5350);
FORCEPROP 2 LASTPIN (450 5150) $PN 51
J 0
(460 5160);
DISPLAY 0.617021 (460 5160);
PAINT ORANGE (460 5160);
FORCEPROP 2 LASTPIN (450 5100) $PN 52
J 0
(460 5110);
DISPLAY 0.617021 (460 5110);
PAINT ORANGE (460 5110);
FORCEPROP 2 LASTPIN (450 5050) $PN 132
J 0
(460 5060);
DISPLAY 0.617021 (460 5060);
PAINT ORANGE (460 5060);
FORCEPROP 2 LASTPIN (450 5000) $PN 133
J 0
(460 5010);
DISPLAY 0.617021 (460 5010);
PAINT ORANGE (460 5010);
FORCEPROP 2 LASTPIN (450 4950) $PN 121
J 0
(460 4960);
DISPLAY 0.617021 (460 4960);
PAINT ORANGE (460 4960);
FORCEPROP 2 LASTPIN (450 4900) $PN 122
J 0
(460 4910);
DISPLAY 0.617021 (460 4910);
PAINT ORANGE (460 4910);
FORCEPROP 2 LASTPIN (450 4850) $PN 110
J 0
(460 4860);
DISPLAY 0.617021 (460 4860);
PAINT ORANGE (460 4860);
FORCEPROP 2 LASTPIN (450 4800) $PN 111
J 0
(460 4810);
DISPLAY 0.617021 (460 4810);
PAINT ORANGE (460 4810);
FORCEPROP 2 LASTPIN (450 4750) $PN 99
J 0
(460 4760);
DISPLAY 0.617021 (460 4760);
PAINT ORANGE (460 4760);
FORCEPROP 2 LASTPIN (450 4700) $PN 100
J 0
(460 4710);
DISPLAY 0.617021 (460 4710);
PAINT ORANGE (460 4710);
FORCEPROP 2 LASTPIN (450 4650) $PN 40
J 0
(460 4660);
DISPLAY 0.617021 (460 4660);
PAINT ORANGE (460 4660);
FORCEPROP 2 LASTPIN (450 4600) $PN 41
J 0
(460 4610);
DISPLAY 0.617021 (460 4610);
PAINT ORANGE (460 4610);
FORCEPROP 2 LASTPIN (450 4550) $PN 29
J 0
(460 4560);
DISPLAY 0.617021 (460 4560);
PAINT ORANGE (460 4560);
FORCEPROP 2 LASTPIN (450 4500) $PN 30
J 0
(460 4510);
DISPLAY 0.617021 (460 4510);
PAINT ORANGE (460 4510);
FORCEPROP 2 LASTPIN (450 4450) $PN 18
J 0
(460 4460);
DISPLAY 0.617021 (460 4460);
PAINT ORANGE (460 4460);
FORCEPROP 2 LASTPIN (450 4400) $PN 19
J 0
(460 4410);
DISPLAY 0.617021 (460 4410);
PAINT ORANGE (460 4410);
FORCEPROP 2 LASTPIN (450 4350) $PN 7
J 0
(460 4360);
DISPLAY 0.617021 (460 4360);
PAINT ORANGE (460 4360);
FORCEPROP 2 LASTPIN (450 4300) $PN 8
J 0
(460 4310);
DISPLAY 0.617021 (460 4310);
PAINT ORANGE (460 4310);
FORCEPROP 2 LASTPIN (450 4250) $PN 197
J 0
(460 4260);
DISPLAY 0.617021 (460 4260);
PAINT ORANGE (460 4260);
FORCEPROP 2 LASTPIN (450 4200) $PN 196
J 0
(460 4210);
DISPLAY 0.617021 (460 4210);
PAINT ORANGE (460 4210);
FORCEPROP 2 LASTPIN (450 4150) $PN 278
J 0
(460 4160);
DISPLAY 0.617021 (460 4160);
PAINT ORANGE (460 4160);
FORCEPROP 2 LASTPIN (450 4100) $PN 277
J 0
(460 4110);
DISPLAY 0.617021 (460 4110);
PAINT ORANGE (460 4110);
FORCEPROP 2 LASTPIN (450 4050) $PN 267
J 0
(460 4060);
DISPLAY 0.617021 (460 4060);
PAINT ORANGE (460 4060);
FORCEPROP 2 LASTPIN (450 4000) $PN 266
J 0
(460 4010);
DISPLAY 0.617021 (460 4010);
PAINT ORANGE (460 4010);
FORCEPROP 2 LASTPIN (450 3950) $PN 256
J 0
(460 3960);
DISPLAY 0.617021 (460 3960);
PAINT ORANGE (460 3960);
FORCEPROP 2 LASTPIN (450 3900) $PN 255
J 0
(460 3910);
DISPLAY 0.617021 (460 3910);
PAINT ORANGE (460 3910);
FORCEPROP 2 LASTPIN (450 3850) $PN 245
J 0
(460 3860);
DISPLAY 0.617021 (460 3860);
PAINT ORANGE (460 3860);
FORCEPROP 2 LASTPIN (450 3800) $PN 244
J 0
(460 3810);
DISPLAY 0.617021 (460 3810);
PAINT ORANGE (460 3810);
FORCEPROP 2 LASTPIN (450 3750) $PN 186
J 0
(460 3760);
DISPLAY 0.617021 (460 3760);
PAINT ORANGE (460 3760);
FORCEPROP 2 LASTPIN (450 3700) $PN 185
J 0
(460 3710);
DISPLAY 0.617021 (460 3710);
PAINT ORANGE (460 3710);
FORCEPROP 2 LASTPIN (450 3650) $PN 175
J 0
(460 3660);
DISPLAY 0.617021 (460 3660);
PAINT ORANGE (460 3660);
FORCEPROP 2 LASTPIN (450 3600) $PN 174
J 0
(460 3610);
DISPLAY 0.617021 (460 3610);
PAINT ORANGE (460 3610);
FORCEPROP 2 LASTPIN (450 3550) $PN 164
J 0
(460 3560);
DISPLAY 0.617021 (460 3560);
PAINT ORANGE (460 3560);
FORCEPROP 2 LASTPIN (450 3500) $PN 163
J 0
(460 3510);
DISPLAY 0.617021 (460 3510);
PAINT ORANGE (460 3510);
FORCEPROP 2 LASTPIN (450 3450) $PN 153
J 0
(460 3460);
DISPLAY 0.617021 (460 3460);
PAINT ORANGE (460 3460);
FORCEPROP 2 LASTPIN (450 3400) $PN 152
J 0
(460 3410);
DISPLAY 0.617021 (460 3410);
PAINT ORANGE (460 3410);
FORCEPROP 1 LAST PACK_TYPE PIP
J 0
(-400 5450);
PAINT SKYBLUE (-400 5450);
DISPLAY INVISIBLE (-400 5450);
FORCEPROP 2 LAST BOM_COST MEM
J 0
(0 4300);
PAINT ORANGE (0 4300);
DISPLAY INVISIBLE (0 4300);
FORCEPROP 2 LAST CDS_LIB mstr_sconn
J 0
(0 4300);
PAINT ORANGE (0 4300);
DISPLAY INVISIBLE (0 4300);
FORCEPROP 2 LAST SEC_TYPE PIP
J 0
(-400 5450);
DISPLAY 1.021277 (-400 5450);
PAINT ORANGE (-400 5450);
DISPLAY INVISIBLE (-400 5450);
FORCEPROP 2 LAST SEC 2
J 0
(-400 5450);
DISPLAY 0.680851 (-400 5450);
PAINT MONO (-400 5450);
DISPLAY INVISIBLE (-400 5450);
FORCEPROP 2 LAST CDS_LOCATION J4G2
J 0
(-400 5400);
DISPLAY 0.617021 (-400 5400);
PAINT AQUA (-400 5400);
DISPLAY INVISIBLE (-400 5400);
FORCEPROP 1 LAST PATH I61
J 0
(0 5350);
PAINT GREEN (0 5350);
DISPLAY INVISIBLE (0 5350);
FORCEPROP 2 LAST ROOM DDR4_CH_B
J 0
(-400 5500);
PAINT ORANGE (-400 5500);
DISPLAY INVISIBLE (-400 5500);
FORCEADD TAP..6
R 2
(-1700 3750);
FORCEPROP 3 LASTPIN (-1750 3750) SIG_NAME M_B_DQ<47>
J 0
(-1740 3760);
DISPLAY 0.659574 (-1740 3760);
PAINT MONO (-1740 3760);
DISPLAY INVISIBLE (-1740 3760);
FORCEPROP 1 LASTPIN (-1750 3750) BN 47
J 2
(-1700 3760);
DISPLAY 0.617021 (-1700 3760);
PAINT PINK (-1700 3760);
FORCEPROP 2 LAST CDS_LIB mstr_standard
J 2
(-1700 3750);
DISPLAY 0.787234 (-1700 3750);
PAINT MONO (-1700 3750);
DISPLAY INVISIBLE (-1700 3750);
FORCEPROP 1 LAST BODY_TYPE PLUMBING
J 2
(-1700 3700);
DISPLAY 1.234043 (-1700 3700);
PAINT GREEN (-1700 3700);
DISPLAY INVISIBLE (-1700 3700);
FORCEPROP 1 LAST HDL_TAP TRUE
J 2
(-2025 3625);
DISPLAY 1.234043 (-2025 3625);
PAINT GREEN (-2025 3625);
DISPLAY INVISIBLE (-2025 3625);
FORCEPROP 1 LAST PATH I62
J 2
(-1700 3750);
DISPLAY 0.936170 (-1700 3750);
PAINT GREEN (-1700 3750);
DISPLAY INVISIBLE (-1700 3750);
FORCEADD TAP..6
R 2
(-1700 3800);
FORCEPROP 3 LASTPIN (-1750 3800) SIG_NAME M_B_DQ<46>
J 0
(-1740 3810);
DISPLAY 0.659574 (-1740 3810);
PAINT MONO (-1740 3810);
DISPLAY INVISIBLE (-1740 3810);
FORCEPROP 1 LASTPIN (-1750 3800) BN 46
J 2
(-1700 3810);
DISPLAY 0.617021 (-1700 3810);
PAINT PINK (-1700 3810);
FORCEPROP 2 LAST CDS_LIB mstr_standard
J 2
(-1700 3800);
DISPLAY 0.787234 (-1700 3800);
PAINT MONO (-1700 3800);
DISPLAY INVISIBLE (-1700 3800);
FORCEPROP 1 LAST BODY_TYPE PLUMBING
J 2
(-1700 3750);
DISPLAY 1.234043 (-1700 3750);
PAINT GREEN (-1700 3750);
DISPLAY INVISIBLE (-1700 3750);
FORCEPROP 1 LAST HDL_TAP TRUE
J 2
(-2025 3675);
DISPLAY 1.234043 (-2025 3675);
PAINT GREEN (-2025 3675);
DISPLAY INVISIBLE (-2025 3675);
FORCEPROP 1 LAST PATH I63
J 2
(-1700 3800);
DISPLAY 0.936170 (-1700 3800);
PAINT GREEN (-1700 3800);
DISPLAY INVISIBLE (-1700 3800);
FORCEADD TAP..6
R 2
(-1700 3850);
FORCEPROP 3 LASTPIN (-1750 3850) SIG_NAME M_B_DQ<49>
J 0
(-1740 3860);
DISPLAY 0.659574 (-1740 3860);
PAINT MONO (-1740 3860);
DISPLAY INVISIBLE (-1740 3860);
FORCEPROP 1 LASTPIN (-1750 3850) BN 49
J 2
(-1700 3860);
DISPLAY 0.617021 (-1700 3860);
PAINT PINK (-1700 3860);
FORCEPROP 2 LAST CDS_LIB mstr_standard
J 2
(-1700 3850);
DISPLAY 0.787234 (-1700 3850);
PAINT MONO (-1700 3850);
DISPLAY INVISIBLE (-1700 3850);
FORCEPROP 1 LAST BODY_TYPE PLUMBING
J 2
(-1700 3800);
DISPLAY 1.234043 (-1700 3800);
PAINT GREEN (-1700 3800);
DISPLAY INVISIBLE (-1700 3800);
FORCEPROP 1 LAST HDL_TAP TRUE
J 2
(-2025 3725);
DISPLAY 1.234043 (-2025 3725);
PAINT GREEN (-2025 3725);
DISPLAY INVISIBLE (-2025 3725);
FORCEPROP 1 LAST PATH I64
J 2
(-1700 3850);
DISPLAY 0.936170 (-1700 3850);
PAINT GREEN (-1700 3850);
DISPLAY INVISIBLE (-1700 3850);
FORCEADD TAP..6
R 2
(-1700 3700);
FORCEPROP 3 LASTPIN (-1750 3700) SIG_NAME M_B_DQ<44>
J 0
(-1740 3710);
DISPLAY 0.659574 (-1740 3710);
PAINT MONO (-1740 3710);
DISPLAY INVISIBLE (-1740 3710);
FORCEPROP 1 LASTPIN (-1750 3700) BN 44
J 2
(-1700 3710);
DISPLAY 0.617021 (-1700 3710);
PAINT PINK (-1700 3710);
FORCEPROP 2 LAST CDS_LIB mstr_standard
J 2
(-1700 3700);
DISPLAY 0.787234 (-1700 3700);
PAINT MONO (-1700 3700);
DISPLAY INVISIBLE (-1700 3700);
FORCEPROP 1 LAST BODY_TYPE PLUMBING
J 2
(-1700 3650);
DISPLAY 1.234043 (-1700 3650);
PAINT GREEN (-1700 3650);
DISPLAY INVISIBLE (-1700 3650);
FORCEPROP 1 LAST HDL_TAP TRUE
J 2
(-2025 3575);
DISPLAY 1.234043 (-2025 3575);
PAINT GREEN (-2025 3575);
DISPLAY INVISIBLE (-2025 3575);
FORCEPROP 1 LAST PATH I65
J 2
(-1700 3700);
DISPLAY 0.936170 (-1700 3700);
PAINT GREEN (-1700 3700);
DISPLAY INVISIBLE (-1700 3700);
FORCEADD TAP..6
R 2
(-1700 3650);
FORCEPROP 3 LASTPIN (-1750 3650) SIG_NAME M_B_DQ<45>
J 0
(-1740 3660);
DISPLAY 0.659574 (-1740 3660);
PAINT MONO (-1740 3660);
DISPLAY INVISIBLE (-1740 3660);
FORCEPROP 1 LASTPIN (-1750 3650) BN 45
J 2
(-1700 3660);
DISPLAY 0.617021 (-1700 3660);
PAINT PINK (-1700 3660);
FORCEPROP 2 LAST CDS_LIB mstr_standard
J 2
(-1700 3650);
DISPLAY 0.787234 (-1700 3650);
PAINT MONO (-1700 3650);
DISPLAY INVISIBLE (-1700 3650);
FORCEPROP 1 LAST BODY_TYPE PLUMBING
J 2
(-1700 3600);
DISPLAY 1.234043 (-1700 3600);
PAINT GREEN (-1700 3600);
DISPLAY INVISIBLE (-1700 3600);
FORCEPROP 1 LAST HDL_TAP TRUE
J 2
(-2025 3525);
DISPLAY 1.234043 (-2025 3525);
PAINT GREEN (-2025 3525);
DISPLAY INVISIBLE (-2025 3525);
FORCEPROP 1 LAST PATH I66
J 2
(-1700 3650);
DISPLAY 0.936170 (-1700 3650);
PAINT GREEN (-1700 3650);
DISPLAY INVISIBLE (-1700 3650);
FORCEADD TAP..6
R 2
(-1700 3600);
FORCEPROP 3 LASTPIN (-1750 3600) SIG_NAME M_B_DQ<42>
J 0
(-1740 3610);
DISPLAY 0.659574 (-1740 3610);
PAINT MONO (-1740 3610);
DISPLAY INVISIBLE (-1740 3610);
FORCEPROP 1 LASTPIN (-1750 3600) BN 42
J 2
(-1700 3610);
DISPLAY 0.617021 (-1700 3610);
PAINT PINK (-1700 3610);
FORCEPROP 2 LAST CDS_LIB mstr_standard
J 2
(-1700 3600);
DISPLAY 0.787234 (-1700 3600);
PAINT MONO (-1700 3600);
DISPLAY INVISIBLE (-1700 3600);
FORCEPROP 1 LAST BODY_TYPE PLUMBING
J 2
(-1700 3550);
DISPLAY 1.234043 (-1700 3550);
PAINT GREEN (-1700 3550);
DISPLAY INVISIBLE (-1700 3550);
FORCEPROP 1 LAST HDL_TAP TRUE
J 2
(-2025 3475);
DISPLAY 1.234043 (-2025 3475);
PAINT GREEN (-2025 3475);
DISPLAY INVISIBLE (-2025 3475);
FORCEPROP 1 LAST PATH I67
J 2
(-1700 3600);
DISPLAY 0.936170 (-1700 3600);
PAINT GREEN (-1700 3600);
DISPLAY INVISIBLE (-1700 3600);
FORCEADD TAP..6
R 2
(-1700 3550);
FORCEPROP 3 LASTPIN (-1750 3550) SIG_NAME M_B_DQ<43>
J 0
(-1740 3560);
DISPLAY 0.659574 (-1740 3560);
PAINT MONO (-1740 3560);
DISPLAY INVISIBLE (-1740 3560);
FORCEPROP 1 LASTPIN (-1750 3550) BN 43
J 2
(-1700 3560);
DISPLAY 0.617021 (-1700 3560);
PAINT PINK (-1700 3560);
FORCEPROP 2 LAST CDS_LIB mstr_standard
J 2
(-1700 3550);
DISPLAY 0.787234 (-1700 3550);
PAINT MONO (-1700 3550);
DISPLAY INVISIBLE (-1700 3550);
FORCEPROP 1 LAST BODY_TYPE PLUMBING
J 2
(-1700 3500);
DISPLAY 1.234043 (-1700 3500);
PAINT GREEN (-1700 3500);
DISPLAY INVISIBLE (-1700 3500);
FORCEPROP 1 LAST HDL_TAP TRUE
J 2
(-2025 3425);
DISPLAY 1.234043 (-2025 3425);
PAINT GREEN (-2025 3425);
DISPLAY INVISIBLE (-2025 3425);
FORCEPROP 1 LAST PATH I68
J 2
(-1700 3550);
DISPLAY 0.936170 (-1700 3550);
PAINT GREEN (-1700 3550);
DISPLAY INVISIBLE (-1700 3550);
FORCEADD TAP..6
R 2
(-1700 3500);
FORCEPROP 3 LASTPIN (-1750 3500) SIG_NAME M_B_DQ<40>
J 0
(-1740 3510);
DISPLAY 0.659574 (-1740 3510);
PAINT MONO (-1740 3510);
DISPLAY INVISIBLE (-1740 3510);
FORCEPROP 1 LASTPIN (-1750 3500) BN 40
J 2
(-1700 3510);
DISPLAY 0.617021 (-1700 3510);
PAINT PINK (-1700 3510);
FORCEPROP 2 LAST CDS_LIB mstr_standard
J 2
(-1700 3500);
DISPLAY 0.787234 (-1700 3500);
PAINT MONO (-1700 3500);
DISPLAY INVISIBLE (-1700 3500);
FORCEPROP 1 LAST BODY_TYPE PLUMBING
J 2
(-1700 3450);
DISPLAY 1.234043 (-1700 3450);
PAINT GREEN (-1700 3450);
DISPLAY INVISIBLE (-1700 3450);
FORCEPROP 1 LAST HDL_TAP TRUE
J 2
(-2025 3375);
DISPLAY 1.234043 (-2025 3375);
PAINT GREEN (-2025 3375);
DISPLAY INVISIBLE (-2025 3375);
FORCEPROP 1 LAST PATH I69
J 2
(-1700 3500);
DISPLAY 0.936170 (-1700 3500);
PAINT GREEN (-1700 3500);
DISPLAY INVISIBLE (-1700 3500);
FORCEADD TAP..6
R 2
(900 5000);
FORCEPROP 3 LASTPIN (850 5000) SIG_NAME M_B_DQS_DN<16>
J 0
(860 5010);
DISPLAY 0.659574 (860 5010);
PAINT MONO (860 5010);
DISPLAY INVISIBLE (860 5010);
FORCEPROP 1 LASTPIN (850 5000) BN 16
J 2
(900 5010);
DISPLAY 0.617021 (900 5010);
PAINT PINK (900 5010);
FORCEPROP 2 LAST CDS_LIB mstr_standard
J 0
(900 5000);
DISPLAY 0.787234 (900 5000);
PAINT MONO (900 5000);
DISPLAY INVISIBLE (900 5000);
FORCEPROP 1 LAST BODY_TYPE PLUMBING
J 2
(900 4950);
DISPLAY 1.234043 (900 4950);
PAINT GREEN (900 4950);
DISPLAY INVISIBLE (900 4950);
FORCEPROP 1 LAST HDL_TAP TRUE
J 2
(575 4875);
DISPLAY 1.234043 (575 4875);
PAINT GREEN (575 4875);
DISPLAY INVISIBLE (575 4875);
FORCEPROP 1 LAST PATH I7
J 2
(900 5000);
DISPLAY 0.936170 (900 5000);
PAINT GREEN (900 5000);
DISPLAY INVISIBLE (900 5000);
FORCEADD TAP..6
R 2
(-1700 3400);
FORCEPROP 3 LASTPIN (-1750 3400) SIG_NAME M_B_DQ<38>
J 0
(-1740 3410);
DISPLAY 0.659574 (-1740 3410);
PAINT MONO (-1740 3410);
DISPLAY INVISIBLE (-1740 3410);
FORCEPROP 1 LASTPIN (-1750 3400) BN 38
J 2
(-1700 3410);
DISPLAY 0.617021 (-1700 3410);
PAINT PINK (-1700 3410);
FORCEPROP 2 LAST CDS_LIB mstr_standard
J 2
(-1700 3400);
DISPLAY 0.787234 (-1700 3400);
PAINT MONO (-1700 3400);
DISPLAY INVISIBLE (-1700 3400);
FORCEPROP 1 LAST BODY_TYPE PLUMBING
J 2
(-1700 3350);
DISPLAY 1.234043 (-1700 3350);
PAINT GREEN (-1700 3350);
DISPLAY INVISIBLE (-1700 3350);
FORCEPROP 1 LAST HDL_TAP TRUE
J 2
(-2025 3275);
DISPLAY 1.234043 (-2025 3275);
PAINT GREEN (-2025 3275);
DISPLAY INVISIBLE (-2025 3275);
FORCEPROP 1 LAST PATH I70
J 2
(-1700 3400);
DISPLAY 0.936170 (-1700 3400);
PAINT GREEN (-1700 3400);
DISPLAY INVISIBLE (-1700 3400);
FORCEADD TAP..6
R 2
(-1700 3450);
FORCEPROP 3 LASTPIN (-1750 3450) SIG_NAME M_B_DQ<41>
J 0
(-1740 3460);
DISPLAY 0.659574 (-1740 3460);
PAINT MONO (-1740 3460);
DISPLAY INVISIBLE (-1740 3460);
FORCEPROP 1 LASTPIN (-1750 3450) BN 41
J 2
(-1700 3460);
DISPLAY 0.617021 (-1700 3460);
PAINT PINK (-1700 3460);
FORCEPROP 2 LAST CDS_LIB mstr_standard
J 2
(-1700 3450);
DISPLAY 0.787234 (-1700 3450);
PAINT MONO (-1700 3450);
DISPLAY INVISIBLE (-1700 3450);
FORCEPROP 1 LAST BODY_TYPE PLUMBING
J 2
(-1700 3400);
DISPLAY 1.234043 (-1700 3400);
PAINT GREEN (-1700 3400);
DISPLAY INVISIBLE (-1700 3400);
FORCEPROP 1 LAST HDL_TAP TRUE
J 2
(-2025 3325);
DISPLAY 1.234043 (-2025 3325);
PAINT GREEN (-2025 3325);
DISPLAY INVISIBLE (-2025 3325);
FORCEPROP 1 LAST PATH I71
J 2
(-1700 3450);
DISPLAY 0.936170 (-1700 3450);
PAINT GREEN (-1700 3450);
DISPLAY INVISIBLE (-1700 3450);
FORCEADD TAP..6
R 2
(-1700 3250);
FORCEPROP 3 LASTPIN (-1750 3250) SIG_NAME M_B_DQ<37>
J 0
(-1740 3260);
DISPLAY 0.659574 (-1740 3260);
PAINT MONO (-1740 3260);
DISPLAY INVISIBLE (-1740 3260);
FORCEPROP 1 LASTPIN (-1750 3250) BN 37
J 2
(-1700 3260);
DISPLAY 0.617021 (-1700 3260);
PAINT PINK (-1700 3260);
FORCEPROP 2 LAST CDS_LIB mstr_standard
J 2
(-1700 3250);
DISPLAY 0.787234 (-1700 3250);
PAINT MONO (-1700 3250);
DISPLAY INVISIBLE (-1700 3250);
FORCEPROP 1 LAST BODY_TYPE PLUMBING
J 2
(-1700 3200);
DISPLAY 1.234043 (-1700 3200);
PAINT GREEN (-1700 3200);
DISPLAY INVISIBLE (-1700 3200);
FORCEPROP 1 LAST HDL_TAP TRUE
J 2
(-2025 3125);
DISPLAY 1.234043 (-2025 3125);
PAINT GREEN (-2025 3125);
DISPLAY INVISIBLE (-2025 3125);
FORCEPROP 1 LAST PATH I72
J 2
(-1700 3250);
DISPLAY 0.936170 (-1700 3250);
PAINT GREEN (-1700 3250);
DISPLAY INVISIBLE (-1700 3250);
FORCEADD TAP..6
R 2
(-1700 3300);
FORCEPROP 3 LASTPIN (-1750 3300) SIG_NAME M_B_DQ<36>
J 0
(-1740 3310);
DISPLAY 0.659574 (-1740 3310);
PAINT MONO (-1740 3310);
DISPLAY INVISIBLE (-1740 3310);
FORCEPROP 1 LASTPIN (-1750 3300) BN 36
J 2
(-1700 3310);
DISPLAY 0.617021 (-1700 3310);
PAINT PINK (-1700 3310);
FORCEPROP 2 LAST CDS_LIB mstr_standard
J 2
(-1700 3300);
DISPLAY 0.787234 (-1700 3300);
PAINT MONO (-1700 3300);
DISPLAY INVISIBLE (-1700 3300);
FORCEPROP 1 LAST BODY_TYPE PLUMBING
J 2
(-1700 3250);
DISPLAY 1.234043 (-1700 3250);
PAINT GREEN (-1700 3250);
DISPLAY INVISIBLE (-1700 3250);
FORCEPROP 1 LAST HDL_TAP TRUE
J 2
(-2025 3175);
DISPLAY 1.234043 (-2025 3175);
PAINT GREEN (-2025 3175);
DISPLAY INVISIBLE (-2025 3175);
FORCEPROP 1 LAST PATH I73
J 2
(-1700 3300);
DISPLAY 0.936170 (-1700 3300);
PAINT GREEN (-1700 3300);
DISPLAY INVISIBLE (-1700 3300);
FORCEADD TAP..6
R 2
(-1700 3350);
FORCEPROP 3 LASTPIN (-1750 3350) SIG_NAME M_B_DQ<39>
J 0
(-1740 3360);
DISPLAY 0.659574 (-1740 3360);
PAINT MONO (-1740 3360);
DISPLAY INVISIBLE (-1740 3360);
FORCEPROP 1 LASTPIN (-1750 3350) BN 39
J 2
(-1700 3360);
DISPLAY 0.617021 (-1700 3360);
PAINT PINK (-1700 3360);
FORCEPROP 2 LAST CDS_LIB mstr_standard
J 2
(-1700 3350);
DISPLAY 0.787234 (-1700 3350);
PAINT MONO (-1700 3350);
DISPLAY INVISIBLE (-1700 3350);
FORCEPROP 1 LAST BODY_TYPE PLUMBING
J 2
(-1700 3300);
DISPLAY 1.234043 (-1700 3300);
PAINT GREEN (-1700 3300);
DISPLAY INVISIBLE (-1700 3300);
FORCEPROP 1 LAST HDL_TAP TRUE
J 2
(-2025 3225);
DISPLAY 1.234043 (-2025 3225);
PAINT GREEN (-2025 3225);
DISPLAY INVISIBLE (-2025 3225);
FORCEPROP 1 LAST PATH I74
J 2
(-1700 3350);
DISPLAY 0.936170 (-1700 3350);
PAINT GREEN (-1700 3350);
DISPLAY INVISIBLE (-1700 3350);
FORCEADD TAP..6
R 2
(-1700 3150);
FORCEPROP 3 LASTPIN (-1750 3150) SIG_NAME M_B_DQ<35>
J 0
(-1740 3160);
DISPLAY 0.659574 (-1740 3160);
PAINT MONO (-1740 3160);
DISPLAY INVISIBLE (-1740 3160);
FORCEPROP 1 LASTPIN (-1750 3150) BN 35
J 2
(-1700 3160);
DISPLAY 0.617021 (-1700 3160);
PAINT PINK (-1700 3160);
FORCEPROP 2 LAST CDS_LIB mstr_standard
J 2
(-1700 3150);
DISPLAY 0.787234 (-1700 3150);
PAINT MONO (-1700 3150);
DISPLAY INVISIBLE (-1700 3150);
FORCEPROP 1 LAST BODY_TYPE PLUMBING
J 2
(-1700 3100);
DISPLAY 1.234043 (-1700 3100);
PAINT GREEN (-1700 3100);
DISPLAY INVISIBLE (-1700 3100);
FORCEPROP 1 LAST HDL_TAP TRUE
J 2
(-2025 3025);
DISPLAY 1.234043 (-2025 3025);
PAINT GREEN (-2025 3025);
DISPLAY INVISIBLE (-2025 3025);
FORCEPROP 1 LAST PATH I75
J 2
(-1700 3150);
DISPLAY 0.936170 (-1700 3150);
PAINT GREEN (-1700 3150);
DISPLAY INVISIBLE (-1700 3150);
FORCEADD TAP..6
R 2
(-1700 3200);
FORCEPROP 3 LASTPIN (-1750 3200) SIG_NAME M_B_DQ<34>
J 0
(-1740 3210);
DISPLAY 0.659574 (-1740 3210);
PAINT MONO (-1740 3210);
DISPLAY INVISIBLE (-1740 3210);
FORCEPROP 1 LASTPIN (-1750 3200) BN 34
J 2
(-1700 3210);
DISPLAY 0.617021 (-1700 3210);
PAINT PINK (-1700 3210);
FORCEPROP 2 LAST CDS_LIB mstr_standard
J 2
(-1700 3200);
DISPLAY 0.787234 (-1700 3200);
PAINT MONO (-1700 3200);
DISPLAY INVISIBLE (-1700 3200);
FORCEPROP 1 LAST BODY_TYPE PLUMBING
J 2
(-1700 3150);
DISPLAY 1.234043 (-1700 3150);
PAINT GREEN (-1700 3150);
DISPLAY INVISIBLE (-1700 3150);
FORCEPROP 1 LAST HDL_TAP TRUE
J 2
(-2025 3075);
DISPLAY 1.234043 (-2025 3075);
PAINT GREEN (-2025 3075);
DISPLAY INVISIBLE (-2025 3075);
FORCEPROP 1 LAST PATH I76
J 2
(-1700 3200);
DISPLAY 0.936170 (-1700 3200);
PAINT GREEN (-1700 3200);
DISPLAY INVISIBLE (-1700 3200);
FORCEADD TAP..6
R 2
(-1700 3100);
FORCEPROP 3 LASTPIN (-1750 3100) SIG_NAME M_B_DQ<32>
J 0
(-1740 3110);
DISPLAY 0.659574 (-1740 3110);
PAINT MONO (-1740 3110);
DISPLAY INVISIBLE (-1740 3110);
FORCEPROP 1 LASTPIN (-1750 3100) BN 32
J 2
(-1700 3110);
DISPLAY 0.617021 (-1700 3110);
PAINT PINK (-1700 3110);
FORCEPROP 2 LAST CDS_LIB mstr_standard
J 2
(-1700 3100);
DISPLAY 0.787234 (-1700 3100);
PAINT MONO (-1700 3100);
DISPLAY INVISIBLE (-1700 3100);
FORCEPROP 1 LAST BODY_TYPE PLUMBING
J 2
(-1700 3050);
DISPLAY 1.234043 (-1700 3050);
PAINT GREEN (-1700 3050);
DISPLAY INVISIBLE (-1700 3050);
FORCEPROP 1 LAST HDL_TAP TRUE
J 2
(-2025 2975);
DISPLAY 1.234043 (-2025 2975);
PAINT GREEN (-2025 2975);
DISPLAY INVISIBLE (-2025 2975);
FORCEPROP 1 LAST PATH I77
J 2
(-1700 3100);
DISPLAY 0.936170 (-1700 3100);
PAINT GREEN (-1700 3100);
DISPLAY INVISIBLE (-1700 3100);
FORCEADD TAP..6
R 2
(-1700 3050);
FORCEPROP 3 LASTPIN (-1750 3050) SIG_NAME M_B_DQ<33>
J 0
(-1740 3060);
DISPLAY 0.659574 (-1740 3060);
PAINT MONO (-1740 3060);
DISPLAY INVISIBLE (-1740 3060);
FORCEPROP 1 LASTPIN (-1750 3050) BN 33
J 2
(-1700 3060);
DISPLAY 0.617021 (-1700 3060);
PAINT PINK (-1700 3060);
FORCEPROP 2 LAST CDS_LIB mstr_standard
J 2
(-1700 3050);
DISPLAY 0.787234 (-1700 3050);
PAINT MONO (-1700 3050);
DISPLAY INVISIBLE (-1700 3050);
FORCEPROP 1 LAST BODY_TYPE PLUMBING
J 2
(-1700 3000);
DISPLAY 1.234043 (-1700 3000);
PAINT GREEN (-1700 3000);
DISPLAY INVISIBLE (-1700 3000);
FORCEPROP 1 LAST HDL_TAP TRUE
J 2
(-2025 2925);
DISPLAY 1.234043 (-2025 2925);
PAINT GREEN (-2025 2925);
DISPLAY INVISIBLE (-2025 2925);
FORCEPROP 1 LAST PATH I78
J 2
(-1700 3050);
DISPLAY 0.936170 (-1700 3050);
PAINT GREEN (-1700 3050);
DISPLAY INVISIBLE (-1700 3050);
FORCEADD TAP..6
R 2
(-1700 3000);
FORCEPROP 3 LASTPIN (-1750 3000) SIG_NAME M_B_DQ<30>
J 0
(-1740 3010);
DISPLAY 0.659574 (-1740 3010);
PAINT MONO (-1740 3010);
DISPLAY INVISIBLE (-1740 3010);
FORCEPROP 1 LASTPIN (-1750 3000) BN 30
J 2
(-1700 3010);
DISPLAY 0.617021 (-1700 3010);
PAINT PINK (-1700 3010);
FORCEPROP 2 LAST CDS_LIB mstr_standard
J 2
(-1700 3000);
DISPLAY 0.787234 (-1700 3000);
PAINT MONO (-1700 3000);
DISPLAY INVISIBLE (-1700 3000);
FORCEPROP 1 LAST BODY_TYPE PLUMBING
J 2
(-1700 2950);
DISPLAY 1.234043 (-1700 2950);
PAINT GREEN (-1700 2950);
DISPLAY INVISIBLE (-1700 2950);
FORCEPROP 1 LAST HDL_TAP TRUE
J 2
(-2025 2875);
DISPLAY 1.234043 (-2025 2875);
PAINT GREEN (-2025 2875);
DISPLAY INVISIBLE (-2025 2875);
FORCEPROP 1 LAST PATH I79
J 2
(-1700 3000);
DISPLAY 0.936170 (-1700 3000);
PAINT GREEN (-1700 3000);
DISPLAY INVISIBLE (-1700 3000);
FORCEADD TAP..6
R 2
(900 4800);
FORCEPROP 3 LASTPIN (850 4800) SIG_NAME M_B_DQS_DN<14>
J 0
(860 4810);
DISPLAY 0.659574 (860 4810);
PAINT MONO (860 4810);
DISPLAY INVISIBLE (860 4810);
FORCEPROP 1 LASTPIN (850 4800) BN 14
J 2
(900 4810);
DISPLAY 0.617021 (900 4810);
PAINT PINK (900 4810);
FORCEPROP 2 LAST CDS_LIB mstr_standard
J 0
(900 4800);
DISPLAY 0.787234 (900 4800);
PAINT MONO (900 4800);
DISPLAY INVISIBLE (900 4800);
FORCEPROP 1 LAST BODY_TYPE PLUMBING
J 2
(900 4750);
DISPLAY 1.234043 (900 4750);
PAINT GREEN (900 4750);
DISPLAY INVISIBLE (900 4750);
FORCEPROP 1 LAST HDL_TAP TRUE
J 2
(575 4675);
DISPLAY 1.234043 (575 4675);
PAINT GREEN (575 4675);
DISPLAY INVISIBLE (575 4675);
FORCEPROP 1 LAST PATH I8
J 2
(900 4800);
DISPLAY 0.936170 (900 4800);
PAINT GREEN (900 4800);
DISPLAY INVISIBLE (900 4800);
FORCEADD TAP..6
R 2
(-1700 2850);
FORCEPROP 3 LASTPIN (-1750 2850) SIG_NAME M_B_DQ<29>
J 0
(-1740 2860);
DISPLAY 0.659574 (-1740 2860);
PAINT MONO (-1740 2860);
DISPLAY INVISIBLE (-1740 2860);
FORCEPROP 1 LASTPIN (-1750 2850) BN 29
J 2
(-1700 2860);
DISPLAY 0.617021 (-1700 2860);
PAINT PINK (-1700 2860);
FORCEPROP 2 LAST CDS_LIB mstr_standard
J 2
(-1700 2850);
DISPLAY 0.787234 (-1700 2850);
PAINT MONO (-1700 2850);
DISPLAY INVISIBLE (-1700 2850);
FORCEPROP 1 LAST BODY_TYPE PLUMBING
J 2
(-1700 2800);
DISPLAY 1.234043 (-1700 2800);
PAINT GREEN (-1700 2800);
DISPLAY INVISIBLE (-1700 2800);
FORCEPROP 1 LAST HDL_TAP TRUE
J 2
(-2025 2725);
DISPLAY 1.234043 (-2025 2725);
PAINT GREEN (-2025 2725);
DISPLAY INVISIBLE (-2025 2725);
FORCEPROP 1 LAST PATH I80
J 2
(-1700 2850);
DISPLAY 0.936170 (-1700 2850);
PAINT GREEN (-1700 2850);
DISPLAY INVISIBLE (-1700 2850);
FORCEADD TAP..6
R 2
(-1700 2900);
FORCEPROP 3 LASTPIN (-1750 2900) SIG_NAME M_B_DQ<28>
J 0
(-1740 2910);
DISPLAY 0.659574 (-1740 2910);
PAINT MONO (-1740 2910);
DISPLAY INVISIBLE (-1740 2910);
FORCEPROP 1 LASTPIN (-1750 2900) BN 28
J 2
(-1700 2910);
DISPLAY 0.617021 (-1700 2910);
PAINT PINK (-1700 2910);
FORCEPROP 2 LAST CDS_LIB mstr_standard
J 2
(-1700 2900);
DISPLAY 0.787234 (-1700 2900);
PAINT MONO (-1700 2900);
DISPLAY INVISIBLE (-1700 2900);
FORCEPROP 1 LAST BODY_TYPE PLUMBING
J 2
(-1700 2850);
DISPLAY 1.234043 (-1700 2850);
PAINT GREEN (-1700 2850);
DISPLAY INVISIBLE (-1700 2850);
FORCEPROP 1 LAST HDL_TAP TRUE
J 2
(-2025 2775);
DISPLAY 1.234043 (-2025 2775);
PAINT GREEN (-2025 2775);
DISPLAY INVISIBLE (-2025 2775);
FORCEPROP 1 LAST PATH I81
J 2
(-1700 2900);
DISPLAY 0.936170 (-1700 2900);
PAINT GREEN (-1700 2900);
DISPLAY INVISIBLE (-1700 2900);
FORCEADD TAP..6
R 2
(-1700 2950);
FORCEPROP 3 LASTPIN (-1750 2950) SIG_NAME M_B_DQ<31>
J 0
(-1740 2960);
DISPLAY 0.659574 (-1740 2960);
PAINT MONO (-1740 2960);
DISPLAY INVISIBLE (-1740 2960);
FORCEPROP 1 LASTPIN (-1750 2950) BN 31
J 2
(-1700 2960);
DISPLAY 0.617021 (-1700 2960);
PAINT PINK (-1700 2960);
FORCEPROP 2 LAST CDS_LIB mstr_standard
J 2
(-1700 2950);
DISPLAY 0.787234 (-1700 2950);
PAINT MONO (-1700 2950);
DISPLAY INVISIBLE (-1700 2950);
FORCEPROP 1 LAST BODY_TYPE PLUMBING
J 2
(-1700 2900);
DISPLAY 1.234043 (-1700 2900);
PAINT GREEN (-1700 2900);
DISPLAY INVISIBLE (-1700 2900);
FORCEPROP 1 LAST HDL_TAP TRUE
J 2
(-2025 2825);
DISPLAY 1.234043 (-2025 2825);
PAINT GREEN (-2025 2825);
DISPLAY INVISIBLE (-2025 2825);
FORCEPROP 1 LAST PATH I82
J 2
(-1700 2950);
DISPLAY 0.936170 (-1700 2950);
PAINT GREEN (-1700 2950);
DISPLAY INVISIBLE (-1700 2950);
FORCEADD TAP..6
R 2
(-1700 2800);
FORCEPROP 3 LASTPIN (-1750 2800) SIG_NAME M_B_DQ<26>
J 0
(-1740 2810);
DISPLAY 0.659574 (-1740 2810);
PAINT MONO (-1740 2810);
DISPLAY INVISIBLE (-1740 2810);
FORCEPROP 1 LASTPIN (-1750 2800) BN 26
J 2
(-1700 2810);
DISPLAY 0.617021 (-1700 2810);
PAINT PINK (-1700 2810);
FORCEPROP 2 LAST CDS_LIB mstr_standard
J 2
(-1700 2800);
DISPLAY 0.787234 (-1700 2800);
PAINT MONO (-1700 2800);
DISPLAY INVISIBLE (-1700 2800);
FORCEPROP 1 LAST BODY_TYPE PLUMBING
J 2
(-1700 2750);
DISPLAY 1.234043 (-1700 2750);
PAINT GREEN (-1700 2750);
DISPLAY INVISIBLE (-1700 2750);
FORCEPROP 1 LAST HDL_TAP TRUE
J 2
(-2025 2675);
DISPLAY 1.234043 (-2025 2675);
PAINT GREEN (-2025 2675);
DISPLAY INVISIBLE (-2025 2675);
FORCEPROP 1 LAST PATH I83
J 2
(-1700 2800);
DISPLAY 0.936170 (-1700 2800);
PAINT GREEN (-1700 2800);
DISPLAY INVISIBLE (-1700 2800);
FORCEADD TAP..6
R 2
(-1700 2750);
FORCEPROP 3 LASTPIN (-1750 2750) SIG_NAME M_B_DQ<27>
J 0
(-1740 2760);
DISPLAY 0.659574 (-1740 2760);
PAINT MONO (-1740 2760);
DISPLAY INVISIBLE (-1740 2760);
FORCEPROP 1 LASTPIN (-1750 2750) BN 27
J 2
(-1700 2760);
DISPLAY 0.617021 (-1700 2760);
PAINT PINK (-1700 2760);
FORCEPROP 2 LAST CDS_LIB mstr_standard
J 2
(-1700 2750);
DISPLAY 0.787234 (-1700 2750);
PAINT MONO (-1700 2750);
DISPLAY INVISIBLE (-1700 2750);
FORCEPROP 1 LAST BODY_TYPE PLUMBING
J 2
(-1700 2700);
DISPLAY 1.234043 (-1700 2700);
PAINT GREEN (-1700 2700);
DISPLAY INVISIBLE (-1700 2700);
FORCEPROP 1 LAST HDL_TAP TRUE
J 2
(-2025 2625);
DISPLAY 1.234043 (-2025 2625);
PAINT GREEN (-2025 2625);
DISPLAY INVISIBLE (-2025 2625);
FORCEPROP 1 LAST PATH I84
J 2
(-1700 2750);
DISPLAY 0.936170 (-1700 2750);
PAINT GREEN (-1700 2750);
DISPLAY INVISIBLE (-1700 2750);
FORCEADD TAP..6
R 2
(-1700 2600);
FORCEPROP 3 LASTPIN (-1750 2600) SIG_NAME M_B_DQ<22>
J 0
(-1740 2610);
DISPLAY 0.659574 (-1740 2610);
PAINT MONO (-1740 2610);
DISPLAY INVISIBLE (-1740 2610);
FORCEPROP 1 LASTPIN (-1750 2600) BN 22
J 2
(-1700 2610);
DISPLAY 0.617021 (-1700 2610);
PAINT PINK (-1700 2610);
FORCEPROP 2 LAST CDS_LIB mstr_standard
J 2
(-1700 2600);
DISPLAY 0.787234 (-1700 2600);
PAINT MONO (-1700 2600);
DISPLAY INVISIBLE (-1700 2600);
FORCEPROP 1 LAST BODY_TYPE PLUMBING
J 2
(-1700 2550);
DISPLAY 1.234043 (-1700 2550);
PAINT GREEN (-1700 2550);
DISPLAY INVISIBLE (-1700 2550);
FORCEPROP 1 LAST HDL_TAP TRUE
J 2
(-2025 2475);
DISPLAY 1.234043 (-2025 2475);
PAINT GREEN (-2025 2475);
DISPLAY INVISIBLE (-2025 2475);
FORCEPROP 1 LAST PATH I85
J 2
(-1700 2600);
DISPLAY 0.936170 (-1700 2600);
PAINT GREEN (-1700 2600);
DISPLAY INVISIBLE (-1700 2600);
FORCEADD TAP..6
R 2
(-1700 2700);
FORCEPROP 3 LASTPIN (-1750 2700) SIG_NAME M_B_DQ<24>
J 0
(-1740 2710);
DISPLAY 0.659574 (-1740 2710);
PAINT MONO (-1740 2710);
DISPLAY INVISIBLE (-1740 2710);
FORCEPROP 1 LASTPIN (-1750 2700) BN 24
J 2
(-1700 2710);
DISPLAY 0.617021 (-1700 2710);
PAINT PINK (-1700 2710);
FORCEPROP 2 LAST CDS_LIB mstr_standard
J 2
(-1700 2700);
DISPLAY 0.787234 (-1700 2700);
PAINT MONO (-1700 2700);
DISPLAY INVISIBLE (-1700 2700);
FORCEPROP 1 LAST BODY_TYPE PLUMBING
J 2
(-1700 2650);
DISPLAY 1.234043 (-1700 2650);
PAINT GREEN (-1700 2650);
DISPLAY INVISIBLE (-1700 2650);
FORCEPROP 1 LAST HDL_TAP TRUE
J 2
(-2025 2575);
DISPLAY 1.234043 (-2025 2575);
PAINT GREEN (-2025 2575);
DISPLAY INVISIBLE (-2025 2575);
FORCEPROP 1 LAST PATH I86
J 2
(-1700 2700);
DISPLAY 0.936170 (-1700 2700);
PAINT GREEN (-1700 2700);
DISPLAY INVISIBLE (-1700 2700);
FORCEADD TAP..6
R 2
(-1700 2650);
FORCEPROP 3 LASTPIN (-1750 2650) SIG_NAME M_B_DQ<25>
J 0
(-1740 2660);
DISPLAY 0.659574 (-1740 2660);
PAINT MONO (-1740 2660);
DISPLAY INVISIBLE (-1740 2660);
FORCEPROP 1 LASTPIN (-1750 2650) BN 25
J 2
(-1700 2660);
DISPLAY 0.617021 (-1700 2660);
PAINT PINK (-1700 2660);
FORCEPROP 2 LAST CDS_LIB mstr_standard
J 2
(-1700 2650);
DISPLAY 0.787234 (-1700 2650);
PAINT MONO (-1700 2650);
DISPLAY INVISIBLE (-1700 2650);
FORCEPROP 1 LAST BODY_TYPE PLUMBING
J 2
(-1700 2600);
DISPLAY 1.234043 (-1700 2600);
PAINT GREEN (-1700 2600);
DISPLAY INVISIBLE (-1700 2600);
FORCEPROP 1 LAST HDL_TAP TRUE
J 2
(-2025 2525);
DISPLAY 1.234043 (-2025 2525);
PAINT GREEN (-2025 2525);
DISPLAY INVISIBLE (-2025 2525);
FORCEPROP 1 LAST PATH I87
J 2
(-1700 2650);
DISPLAY 0.936170 (-1700 2650);
PAINT GREEN (-1700 2650);
DISPLAY INVISIBLE (-1700 2650);
FORCEADD TAP..6
R 2
(-1700 2500);
FORCEPROP 3 LASTPIN (-1750 2500) SIG_NAME M_B_DQ<20>
J 0
(-1740 2510);
DISPLAY 0.659574 (-1740 2510);
PAINT MONO (-1740 2510);
DISPLAY INVISIBLE (-1740 2510);
FORCEPROP 1 LASTPIN (-1750 2500) BN 20
J 2
(-1700 2510);
DISPLAY 0.617021 (-1700 2510);
PAINT PINK (-1700 2510);
FORCEPROP 2 LAST CDS_LIB mstr_standard
J 2
(-1700 2500);
DISPLAY 0.787234 (-1700 2500);
PAINT MONO (-1700 2500);
DISPLAY INVISIBLE (-1700 2500);
FORCEPROP 1 LAST BODY_TYPE PLUMBING
J 2
(-1700 2450);
DISPLAY 1.234043 (-1700 2450);
PAINT GREEN (-1700 2450);
DISPLAY INVISIBLE (-1700 2450);
FORCEPROP 1 LAST HDL_TAP TRUE
J 2
(-2025 2375);
DISPLAY 1.234043 (-2025 2375);
PAINT GREEN (-2025 2375);
DISPLAY INVISIBLE (-2025 2375);
FORCEPROP 1 LAST PATH I88
J 2
(-1700 2500);
DISPLAY 0.936170 (-1700 2500);
PAINT GREEN (-1700 2500);
DISPLAY INVISIBLE (-1700 2500);
FORCEADD TAP..6
R 2
(-1700 2550);
FORCEPROP 3 LASTPIN (-1750 2550) SIG_NAME M_B_DQ<23>
J 0
(-1740 2560);
DISPLAY 0.659574 (-1740 2560);
PAINT MONO (-1740 2560);
DISPLAY INVISIBLE (-1740 2560);
FORCEPROP 1 LASTPIN (-1750 2550) BN 23
J 2
(-1700 2560);
DISPLAY 0.617021 (-1700 2560);
PAINT PINK (-1700 2560);
FORCEPROP 2 LAST CDS_LIB mstr_standard
J 2
(-1700 2550);
DISPLAY 0.787234 (-1700 2550);
PAINT MONO (-1700 2550);
DISPLAY INVISIBLE (-1700 2550);
FORCEPROP 1 LAST BODY_TYPE PLUMBING
J 2
(-1700 2500);
DISPLAY 1.234043 (-1700 2500);
PAINT GREEN (-1700 2500);
DISPLAY INVISIBLE (-1700 2500);
FORCEPROP 1 LAST HDL_TAP TRUE
J 2
(-2025 2425);
DISPLAY 1.234043 (-2025 2425);
PAINT GREEN (-2025 2425);
DISPLAY INVISIBLE (-2025 2425);
FORCEPROP 1 LAST PATH I89
J 2
(-1700 2550);
DISPLAY 0.936170 (-1700 2550);
PAINT GREEN (-1700 2550);
DISPLAY INVISIBLE (-1700 2550);
FORCEADD TAP..6
R 2
(700 4950);
FORCEPROP 3 LASTPIN (650 4950) SIG_NAME M_B_DQS_DP<15>
J 0
(660 4960);
DISPLAY 0.659574 (660 4960);
PAINT MONO (660 4960);
DISPLAY INVISIBLE (660 4960);
FORCEPROP 1 LASTPIN (650 4950) BN 15
J 2
(700 4960);
DISPLAY 0.617021 (700 4960);
PAINT PINK (700 4960);
FORCEPROP 2 LAST CDS_LIB mstr_standard
J 0
(700 4950);
DISPLAY 0.787234 (700 4950);
PAINT MONO (700 4950);
DISPLAY INVISIBLE (700 4950);
FORCEPROP 1 LAST BODY_TYPE PLUMBING
J 2
(700 4900);
DISPLAY 1.234043 (700 4900);
PAINT GREEN (700 4900);
DISPLAY INVISIBLE (700 4900);
FORCEPROP 1 LAST HDL_TAP TRUE
J 2
(375 4825);
DISPLAY 1.234043 (375 4825);
PAINT GREEN (375 4825);
DISPLAY INVISIBLE (375 4825);
FORCEPROP 1 LAST PATH I9
J 2
(700 4950);
DISPLAY 0.936170 (700 4950);
PAINT GREEN (700 4950);
DISPLAY INVISIBLE (700 4950);
FORCEADD TAP..6
R 2
(-1700 2450);
FORCEPROP 3 LASTPIN (-1750 2450) SIG_NAME M_B_DQ<21>
J 0
(-1740 2460);
DISPLAY 0.659574 (-1740 2460);
PAINT MONO (-1740 2460);
DISPLAY INVISIBLE (-1740 2460);
FORCEPROP 1 LASTPIN (-1750 2450) BN 21
J 2
(-1700 2460);
DISPLAY 0.617021 (-1700 2460);
PAINT PINK (-1700 2460);
FORCEPROP 2 LAST CDS_LIB mstr_standard
J 2
(-1700 2450);
DISPLAY 0.787234 (-1700 2450);
PAINT MONO (-1700 2450);
DISPLAY INVISIBLE (-1700 2450);
FORCEPROP 1 LAST BODY_TYPE PLUMBING
J 2
(-1700 2400);
DISPLAY 1.234043 (-1700 2400);
PAINT GREEN (-1700 2400);
DISPLAY INVISIBLE (-1700 2400);
FORCEPROP 1 LAST HDL_TAP TRUE
J 2
(-2025 2325);
DISPLAY 1.234043 (-2025 2325);
PAINT GREEN (-2025 2325);
DISPLAY INVISIBLE (-2025 2325);
FORCEPROP 1 LAST PATH I90
J 2
(-1700 2450);
DISPLAY 0.936170 (-1700 2450);
PAINT GREEN (-1700 2450);
DISPLAY INVISIBLE (-1700 2450);
FORCEADD TAP..6
R 2
(-1700 2400);
FORCEPROP 3 LASTPIN (-1750 2400) SIG_NAME M_B_DQ<18>
J 0
(-1740 2410);
DISPLAY 0.659574 (-1740 2410);
PAINT MONO (-1740 2410);
DISPLAY INVISIBLE (-1740 2410);
FORCEPROP 1 LASTPIN (-1750 2400) BN 18
J 2
(-1700 2410);
DISPLAY 0.617021 (-1700 2410);
PAINT PINK (-1700 2410);
FORCEPROP 2 LAST CDS_LIB mstr_standard
J 2
(-1700 2400);
DISPLAY 0.787234 (-1700 2400);
PAINT MONO (-1700 2400);
DISPLAY INVISIBLE (-1700 2400);
FORCEPROP 1 LAST BODY_TYPE PLUMBING
J 2
(-1700 2350);
DISPLAY 1.234043 (-1700 2350);
PAINT GREEN (-1700 2350);
DISPLAY INVISIBLE (-1700 2350);
FORCEPROP 1 LAST HDL_TAP TRUE
J 2
(-2025 2275);
DISPLAY 1.234043 (-2025 2275);
PAINT GREEN (-2025 2275);
DISPLAY INVISIBLE (-2025 2275);
FORCEPROP 1 LAST PATH I91
J 2
(-1700 2400);
DISPLAY 0.936170 (-1700 2400);
PAINT GREEN (-1700 2400);
DISPLAY INVISIBLE (-1700 2400);
FORCEADD TAP..6
R 2
(-1700 2350);
FORCEPROP 3 LASTPIN (-1750 2350) SIG_NAME M_B_DQ<19>
J 0
(-1740 2360);
DISPLAY 0.659574 (-1740 2360);
PAINT MONO (-1740 2360);
DISPLAY INVISIBLE (-1740 2360);
FORCEPROP 1 LASTPIN (-1750 2350) BN 19
J 2
(-1700 2360);
DISPLAY 0.617021 (-1700 2360);
PAINT PINK (-1700 2360);
FORCEPROP 2 LAST CDS_LIB mstr_standard
J 2
(-1700 2350);
DISPLAY 0.787234 (-1700 2350);
PAINT MONO (-1700 2350);
DISPLAY INVISIBLE (-1700 2350);
FORCEPROP 1 LAST BODY_TYPE PLUMBING
J 2
(-1700 2300);
DISPLAY 1.234043 (-1700 2300);
PAINT GREEN (-1700 2300);
DISPLAY INVISIBLE (-1700 2300);
FORCEPROP 1 LAST HDL_TAP TRUE
J 2
(-2025 2225);
DISPLAY 1.234043 (-2025 2225);
PAINT GREEN (-2025 2225);
DISPLAY INVISIBLE (-2025 2225);
FORCEPROP 1 LAST PATH I92
J 2
(-1700 2350);
DISPLAY 0.936170 (-1700 2350);
PAINT GREEN (-1700 2350);
DISPLAY INVISIBLE (-1700 2350);
FORCEADD TAP..6
R 2
(-1700 2250);
FORCEPROP 3 LASTPIN (-1750 2250) SIG_NAME M_B_DQ<17>
J 0
(-1740 2260);
DISPLAY 0.659574 (-1740 2260);
PAINT MONO (-1740 2260);
DISPLAY INVISIBLE (-1740 2260);
FORCEPROP 1 LASTPIN (-1750 2250) BN 17
J 2
(-1700 2260);
DISPLAY 0.617021 (-1700 2260);
PAINT PINK (-1700 2260);
FORCEPROP 2 LAST CDS_LIB mstr_standard
J 2
(-1700 2250);
DISPLAY 0.787234 (-1700 2250);
PAINT MONO (-1700 2250);
DISPLAY INVISIBLE (-1700 2250);
FORCEPROP 1 LAST BODY_TYPE PLUMBING
J 2
(-1700 2200);
DISPLAY 1.234043 (-1700 2200);
PAINT GREEN (-1700 2200);
DISPLAY INVISIBLE (-1700 2200);
FORCEPROP 1 LAST HDL_TAP TRUE
J 2
(-2025 2125);
DISPLAY 1.234043 (-2025 2125);
PAINT GREEN (-2025 2125);
DISPLAY INVISIBLE (-2025 2125);
FORCEPROP 1 LAST PATH I93
J 2
(-1700 2250);
DISPLAY 0.936170 (-1700 2250);
PAINT GREEN (-1700 2250);
DISPLAY INVISIBLE (-1700 2250);
FORCEADD TAP..6
R 2
(-1700 2300);
FORCEPROP 3 LASTPIN (-1750 2300) SIG_NAME M_B_DQ<16>
J 0
(-1740 2310);
DISPLAY 0.659574 (-1740 2310);
PAINT MONO (-1740 2310);
DISPLAY INVISIBLE (-1740 2310);
FORCEPROP 1 LASTPIN (-1750 2300) BN 16
J 2
(-1700 2310);
DISPLAY 0.617021 (-1700 2310);
PAINT PINK (-1700 2310);
FORCEPROP 2 LAST CDS_LIB mstr_standard
J 2
(-1700 2300);
DISPLAY 0.787234 (-1700 2300);
PAINT MONO (-1700 2300);
DISPLAY INVISIBLE (-1700 2300);
FORCEPROP 1 LAST BODY_TYPE PLUMBING
J 2
(-1700 2250);
DISPLAY 1.234043 (-1700 2250);
PAINT GREEN (-1700 2250);
DISPLAY INVISIBLE (-1700 2250);
FORCEPROP 1 LAST HDL_TAP TRUE
J 2
(-2025 2175);
DISPLAY 1.234043 (-2025 2175);
PAINT GREEN (-2025 2175);
DISPLAY INVISIBLE (-2025 2175);
FORCEPROP 1 LAST PATH I94
J 2
(-1700 2300);
DISPLAY 0.936170 (-1700 2300);
PAINT GREEN (-1700 2300);
DISPLAY INVISIBLE (-1700 2300);
FORCEADD TAP..6
R 2
(-1700 2100);
FORCEPROP 3 LASTPIN (-1750 2100) SIG_NAME M_B_DQ<12>
J 0
(-1740 2110);
DISPLAY 0.659574 (-1740 2110);
PAINT MONO (-1740 2110);
DISPLAY INVISIBLE (-1740 2110);
FORCEPROP 1 LASTPIN (-1750 2100) BN 12
J 2
(-1700 2110);
DISPLAY 0.617021 (-1700 2110);
PAINT PINK (-1700 2110);
FORCEPROP 2 LAST CDS_LIB mstr_standard
J 2
(-1700 2100);
DISPLAY 0.787234 (-1700 2100);
PAINT MONO (-1700 2100);
DISPLAY INVISIBLE (-1700 2100);
FORCEPROP 1 LAST BODY_TYPE PLUMBING
J 2
(-1700 2050);
DISPLAY 1.234043 (-1700 2050);
PAINT GREEN (-1700 2050);
DISPLAY INVISIBLE (-1700 2050);
FORCEPROP 1 LAST HDL_TAP TRUE
J 2
(-2025 1975);
DISPLAY 1.234043 (-2025 1975);
PAINT GREEN (-2025 1975);
DISPLAY INVISIBLE (-2025 1975);
FORCEPROP 1 LAST PATH I95
J 2
(-1700 2100);
DISPLAY 0.936170 (-1700 2100);
PAINT GREEN (-1700 2100);
DISPLAY INVISIBLE (-1700 2100);
FORCEADD TAP..6
R 2
(-1700 2150);
FORCEPROP 3 LASTPIN (-1750 2150) SIG_NAME M_B_DQ<15>
J 0
(-1740 2160);
DISPLAY 0.659574 (-1740 2160);
PAINT MONO (-1740 2160);
DISPLAY INVISIBLE (-1740 2160);
FORCEPROP 1 LASTPIN (-1750 2150) BN 15
J 2
(-1700 2160);
DISPLAY 0.617021 (-1700 2160);
PAINT PINK (-1700 2160);
FORCEPROP 2 LAST CDS_LIB mstr_standard
J 2
(-1700 2150);
DISPLAY 0.787234 (-1700 2150);
PAINT MONO (-1700 2150);
DISPLAY INVISIBLE (-1700 2150);
FORCEPROP 1 LAST BODY_TYPE PLUMBING
J 2
(-1700 2100);
DISPLAY 1.234043 (-1700 2100);
PAINT GREEN (-1700 2100);
DISPLAY INVISIBLE (-1700 2100);
FORCEPROP 1 LAST HDL_TAP TRUE
J 2
(-2025 2025);
DISPLAY 1.234043 (-2025 2025);
PAINT GREEN (-2025 2025);
DISPLAY INVISIBLE (-2025 2025);
FORCEPROP 1 LAST PATH I96
J 2
(-1700 2150);
DISPLAY 0.936170 (-1700 2150);
PAINT GREEN (-1700 2150);
DISPLAY INVISIBLE (-1700 2150);
FORCEADD TAP..6
R 2
(-1700 2200);
FORCEPROP 3 LASTPIN (-1750 2200) SIG_NAME M_B_DQ<14>
J 0
(-1740 2210);
DISPLAY 0.659574 (-1740 2210);
PAINT MONO (-1740 2210);
DISPLAY INVISIBLE (-1740 2210);
FORCEPROP 1 LASTPIN (-1750 2200) BN 14
J 2
(-1700 2210);
DISPLAY 0.617021 (-1700 2210);
PAINT PINK (-1700 2210);
FORCEPROP 2 LAST CDS_LIB mstr_standard
J 2
(-1700 2200);
DISPLAY 0.787234 (-1700 2200);
PAINT MONO (-1700 2200);
DISPLAY INVISIBLE (-1700 2200);
FORCEPROP 1 LAST BODY_TYPE PLUMBING
J 2
(-1700 2150);
DISPLAY 1.234043 (-1700 2150);
PAINT GREEN (-1700 2150);
DISPLAY INVISIBLE (-1700 2150);
FORCEPROP 1 LAST HDL_TAP TRUE
J 2
(-2025 2075);
DISPLAY 1.234043 (-2025 2075);
PAINT GREEN (-2025 2075);
DISPLAY INVISIBLE (-2025 2075);
FORCEPROP 1 LAST PATH I97
J 2
(-1700 2200);
DISPLAY 0.936170 (-1700 2200);
PAINT GREEN (-1700 2200);
DISPLAY INVISIBLE (-1700 2200);
FORCEADD TAP..6
R 2
(-1700 2000);
FORCEPROP 3 LASTPIN (-1750 2000) SIG_NAME M_B_DQ<10>
J 0
(-1740 2010);
DISPLAY 0.659574 (-1740 2010);
PAINT MONO (-1740 2010);
DISPLAY INVISIBLE (-1740 2010);
FORCEPROP 1 LASTPIN (-1750 2000) BN 10
J 2
(-1700 2010);
DISPLAY 0.617021 (-1700 2010);
PAINT PINK (-1700 2010);
FORCEPROP 2 LAST CDS_LIB mstr_standard
J 2
(-1700 2000);
DISPLAY 0.787234 (-1700 2000);
PAINT MONO (-1700 2000);
DISPLAY INVISIBLE (-1700 2000);
FORCEPROP 1 LAST BODY_TYPE PLUMBING
J 2
(-1700 1950);
DISPLAY 1.234043 (-1700 1950);
PAINT GREEN (-1700 1950);
DISPLAY INVISIBLE (-1700 1950);
FORCEPROP 1 LAST HDL_TAP TRUE
J 2
(-2025 1875);
DISPLAY 1.234043 (-2025 1875);
PAINT GREEN (-2025 1875);
DISPLAY INVISIBLE (-2025 1875);
FORCEPROP 1 LAST PATH I98
J 2
(-1700 2000);
DISPLAY 0.936170 (-1700 2000);
PAINT GREEN (-1700 2000);
DISPLAY INVISIBLE (-1700 2000);
FORCEADD TAP..6
R 2
(-1700 2050);
FORCEPROP 3 LASTPIN (-1750 2050) SIG_NAME M_B_DQ<13>
J 0
(-1740 2060);
DISPLAY 0.659574 (-1740 2060);
PAINT MONO (-1740 2060);
DISPLAY INVISIBLE (-1740 2060);
FORCEPROP 1 LASTPIN (-1750 2050) BN 13
J 2
(-1700 2060);
DISPLAY 0.617021 (-1700 2060);
PAINT PINK (-1700 2060);
FORCEPROP 2 LAST CDS_LIB mstr_standard
J 2
(-1700 2050);
DISPLAY 0.787234 (-1700 2050);
PAINT MONO (-1700 2050);
DISPLAY INVISIBLE (-1700 2050);
FORCEPROP 1 LAST BODY_TYPE PLUMBING
J 2
(-1700 2000);
DISPLAY 1.234043 (-1700 2000);
PAINT GREEN (-1700 2000);
DISPLAY INVISIBLE (-1700 2000);
FORCEPROP 1 LAST HDL_TAP TRUE
J 2
(-2025 1925);
DISPLAY 1.234043 (-2025 1925);
PAINT GREEN (-2025 1925);
DISPLAY INVISIBLE (-2025 1925);
FORCEPROP 1 LAST PATH I99
J 2
(-1700 2050);
DISPLAY 0.936170 (-1700 2050);
PAINT GREEN (-1700 2050);
DISPLAY INVISIBLE (-1700 2050);
FORCEADD BOM_NOTE..1
(-5000 5300);
FORCEPROP 0 LAST L1 STUFF FOR SKU A & B
J 0
(-5150 5200);
DISPLAY 1.063830 (-5150 5200);
PAINT WHITE (-5150 5200);
FORCEPROP 2 LAST CDS_LIB mstr_symbols
J 0
(-5000 5300);
PAINT ORANGE (-5000 5300);
DISPLAY INVISIBLE (-5000 5300);
FORCEPROP 2 LAST BOM_COST SB
J 0
(-5150 5275);
DISPLAY 1.361702 (-5150 5275);
PAINT ORANGE (-5150 5275);
DISPLAY INVISIBLE (-5150 5275);
FORCEPROP 1 LAST COMMENT_BODY TRUE
J 0
(-4975 5400);
DISPLAY 1.319149 (-4975 5400);
PAINT ORANGE (-4975 5400);
DISPLAY INVISIBLE (-4975 5400);
FORCEPROP 2 LAST ROOM SB_HEADERS
J 0
(-5150 5275);
DISPLAY 1.361702 (-5150 5275);
PAINT ORANGE (-5150 5275);
DISPLAY INVISIBLE (-5150 5275);
FORCEADD INTEL_CORP_BPAGE..1
(2650 500);
FORCEPROP 1 LAST CDS_CON_LAST_MODIFIED Tue Dec 01 11:51:27 2015
J 0
(1225 825);
DISPLAY 0.787234 (1225 825);
PAINT ORANGE (1225 825);
DISPLAY INVISIBLE (1225 825);
FORCEPROP 1 LAST CUSTOM_TXT_CDS <CURRENT_DESIGN_SHEET> OF <TOTAL_DESIGN_SHEETS>
J 0
(2150 525);
PAINT GREEN (2150 525);
FORCEPROP 1 LAST CUSTOM_TXT_CDS <CON_LAST_MODIFIED>
J 0
(725 850);
PAINT GREEN (725 850);
FORCEPROP 2 LAST CUSTOM_TXT_CDS <XR_PAGE_TITLE>
J 0
(-5240 5750);
DISPLAY 0.638298 (-5240 5750);
PAINT PINK (-5240 5750);
DISPLAY INVISIBLE (-5240 5750);
FORCEPROP 1 LAST SCH_ADDRESS3 Santa Clara, CA 95052-8119
J 0
(-1325 525);
DISPLAY 0.617021 (-1325 525);
PAINT GREEN (-1325 525);
FORCEPROP 1 LAST SCH_ADDRESS2 P.O. BOX 58119
J 0
(-1325 575);
DISPLAY 0.617021 (-1325 575);
PAINT GREEN (-1325 575);
FORCEPROP 1 LAST SCH_ADDRESS1 2200 Mission College Blvd.
J 0
(-1325 625);
DISPLAY 0.617021 (-1325 625);
PAINT GREEN (-1325 625);
FORCEPROP 1 LAST SCH_TITLE CPU0 DDR4 CH B DIMM0
J 0
(-5300 550);
DISPLAY 1.212766 (-5300 550);
PAINT WHITE (-5300 550);
FORCEPROP 1 LAST SCH_NUMBER H4694802
J 0
(1350 650);
DISPLAY 1.212766 (1350 650);
PAINT YELLOW (1350 650);
FORCEPROP 1 LAST SCH_DEPT BESD
J 1
(-1800 600);
DISPLAY 1.212766 (-1800 600);
PAINT YELLOW (-1800 600);
FORCEPROP 1 LAST SCH_REV 2.420
J 0
(2400 650);
DISPLAY 0.978723 (2400 650);
PAINT YELLOW (2400 650);
FORCEPROP 2 LAST PAGE_BORDER TRUE
J 0
(-5240 5750);
DISPLAY 0.680851 (-5240 5750);
PAINT PINK (-5240 5750);
DISPLAY INVISIBLE (-5240 5750);
FORCEPROP 2 LAST CDS_LIB mstr_symbols
J 0
(2650 500);
DISPLAY 0.787234 (2650 500);
PAINT MONO (2650 500);
DISPLAY INVISIBLE (2650 500);
FORCEPROP 1 LAST COMMENT_BODY TRUE
J 0
(2660 510);
DISPLAY 0.382979 (2660 510);
PAINT GREEN (2660 510);
DISPLAY INVISIBLE (2660 510);
FORCEPROP 2 LAST CDS_XR_PAGE_TITLE CR-45 : @BASEBOARD_FAB2_LIB.BASEBOARD_FAB2(SCH_1):PAGE45
J 0
(-5240 5750);
DISPLAY 0.638298 (-5240 5750);
PAINT PINK (-5240 5750);
DISPLAY INVISIBLE (-5240 5750);
WIRE 17 -1 (750 5075)(750 5175);
WIRE 17 -1 (750 4975)(750 5075);
WIRE 17 -1 (750 5175)(750 5200);
WIRE 17 -1 (1550 5200)(750 5200);
FORCEPROP 2 LAST SIG_NAME M_B_DQS_DP<17:0>
J 0
(1000 5210);
DISPLAY 0.617021 (1000 5210);
PAINT ORANGE (1000 5210);
WIRE 17 -1 (950 4325)(950 4425);
WIRE 17 -1 (950 4225)(950 4325);
WIRE 17 -1 (950 4425)(950 4525);
WIRE 17 -1 (950 4525)(950 4625);
WIRE 17 -1 (950 4125)(950 4225);
WIRE 17 -1 (950 4025)(950 4125);
WIRE 17 -1 (950 4625)(950 4725);
WIRE 17 -1 (950 4725)(950 4825);
WIRE 17 -1 (950 3925)(950 4025);
WIRE 17 -1 (950 3825)(950 3925);
WIRE 17 -1 (950 4825)(950 4925);
WIRE 17 -1 (950 4925)(950 5025);
WIRE 17 -1 (950 3725)(950 3825);
WIRE 17 -1 (950 3625)(950 3725);
WIRE 17 -1 (950 5025)(950 5125);
WIRE 17 -1 (950 5125)(950 5150);
WIRE 17 -1 (950 3525)(950 3625);
WIRE 17 -1 (950 3425)(950 3525);
WIRE 17 -1 (1550 5150)(950 5150);
FORCEPROP 2 LAST SIG_NAME M_B_DQS_DN<17:0>
J 0
(1000 5160);
DISPLAY 0.617021 (1000 5160);
PAINT ORANGE (1000 5160);
WIRE 17 -1 (750 4475)(750 4575);
WIRE 17 -1 (750 4375)(750 4475);
WIRE 17 -1 (750 4575)(750 4675);
WIRE 17 -1 (750 4675)(750 4775);
WIRE 17 -1 (750 4275)(750 4375);
WIRE 17 -1 (750 4175)(750 4275);
WIRE 17 -1 (750 4775)(750 4875);
WIRE 17 -1 (750 4875)(750 4975);
WIRE 17 -1 (750 4075)(750 4175);
WIRE 17 -1 (750 3975)(750 4075);
WIRE 17 -1 (750 3875)(750 3975);
WIRE 17 -1 (750 3775)(750 3875);
WIRE 17 -1 (750 3675)(750 3775);
WIRE 17 -1 (750 3575)(750 3675);
WIRE 17 -1 (750 3475)(750 3575);
WIRE 17 -1 (-1650 4425)(-1650 4475);
WIRE 17 -1 (-1650 4375)(-1650 4425);
WIRE 17 -1 (-1650 4475)(-1650 4525);
WIRE 17 -1 (-1650 4525)(-1650 4575);
WIRE 17 -1 (-1650 4325)(-1650 4375);
WIRE 17 -1 (-1650 4275)(-1650 4325);
WIRE 17 -1 (-1650 4575)(-1650 4625);
WIRE 17 -1 (-1650 4625)(-1650 4650);
WIRE 17 -1 (-1650 4225)(-1650 4275);
WIRE 17 -1 (-1650 4175)(-1650 4225);
WIRE 17 -1 (-1200 4650)(-1650 4650);
FORCEPROP 2 LAST SIG_NAME M_B_DQ<63:0>
J 0
(-1610 4660);
DISPLAY 0.617021 (-1610 4660);
PAINT ORANGE (-1610 4660);
WIRE 17 -1 (-1650 4125)(-1650 4175);
WIRE 17 -1 (-1650 4075)(-1650 4125);
WIRE 17 -1 (-1650 4025)(-1650 4075);
WIRE 17 -1 (-1650 3975)(-1650 4025);
WIRE 17 -1 (-1650 3925)(-1650 3975);
WIRE 17 -1 (-1650 3875)(-1650 3925);
WIRE 17 -1 (-1650 3825)(-1650 3875);
WIRE 17 -1 (-1650 3775)(-1650 3825);
WIRE 17 -1 (-1650 3725)(-1650 3775);
WIRE 17 -1 (-1650 3675)(-1650 3725);
WIRE 17 -1 (-1650 3625)(-1650 3675);
WIRE 17 -1 (-1650 3575)(-1650 3625);
WIRE 17 -1 (-3250 4325)(-3250 4375);
WIRE 17 -1 (-3250 4275)(-3250 4325);
WIRE 17 -1 (-3250 4375)(-3250 4425);
WIRE 17 -1 (-3250 4425)(-3250 4475);
WIRE 17 -1 (-3250 4225)(-3250 4275);
WIRE 17 -1 (-3250 4175)(-3250 4225);
WIRE 17 -1 (-3250 4475)(-3250 4525);
WIRE 17 -1 (-3250 4525)(-3250 4575);
WIRE 17 -1 (-3250 4125)(-3250 4175);
WIRE 17 -1 (-3250 4075)(-3250 4125);
WIRE 17 -1 (-3250 4575)(-3250 4625);
WIRE 17 -1 (-3250 4625)(-3250 4650);
WIRE 17 -1 (-3250 4025)(-3250 4075);
WIRE 17 -1 (-3250 3975)(-3250 4025);
WIRE 17 -1 (-3800 4650)(-3250 4650);
FORCEPROP 2 LAST SIG_NAME M_B_MA<17:0>
J 0
(-3750 4660);
DISPLAY 0.617021 (-3750 4660);
PAINT ORANGE (-3750 4660);
WIRE 17 -1 (-3250 3925)(-3250 3975);
WIRE 17 -1 (-3250 3875)(-3250 3925);
WIRE 17 -1 (-3250 3825)(-3250 3875);
WIRE 17 -1 (-3250 3775)(-3250 3825);
WIRE 17 -1 (-1650 3525)(-1650 3575);
WIRE 17 -1 (-1650 3475)(-1650 3525);
WIRE 17 -1 (-1650 3425)(-1650 3475);
WIRE 17 -1 (-1650 3375)(-1650 3425);
WIRE 17 -1 (-1650 3325)(-1650 3375);
WIRE 17 -1 (-1650 3275)(-1650 3325);
WIRE 17 -1 (-1650 3225)(-1650 3275);
WIRE 17 -1 (-1650 3175)(-1650 3225);
WIRE 17 -1 (-1650 3125)(-1650 3175);
WIRE 17 -1 (-1650 3075)(-1650 3125);
WIRE 17 -1 (-1650 3025)(-1650 3075);
WIRE 17 -1 (-1650 2975)(-1650 3025);
WIRE 17 -1 (-1650 2925)(-1650 2975);
WIRE 17 -1 (-1650 2875)(-1650 2925);
WIRE 17 -1 (-1650 2825)(-1650 2875);
WIRE 17 -1 (-1650 2775)(-1650 2825);
WIRE 17 -1 (-1650 2725)(-1650 2775);
WIRE 17 -1 (-1650 2675)(-1650 2725);
WIRE 17 -1 (-1650 2625)(-1650 2675);
WIRE 17 -1 (-1650 2575)(-1650 2625);
WIRE 17 -1 (-1650 2525)(-1650 2575);
WIRE 17 -1 (-1650 2475)(-1650 2525);
WIRE 17 -1 (-1650 2425)(-1650 2475);
WIRE 17 -1 (-1650 2375)(-1650 2425);
WIRE 17 -1 (-1650 2325)(-1650 2375);
WIRE 17 -1 (-1650 2275)(-1650 2325);
WIRE 17 -1 (-1650 2225)(-1650 2275);
WIRE 17 -1 (-1650 2175)(-1650 2225);
WIRE 17 -1 (-1650 2125)(-1650 2175);
WIRE 17 -1 (-1650 2075)(-1650 2125);
WIRE 17 -1 (-1650 2025)(-1650 2075);
WIRE 17 -1 (-1650 1975)(-1650 2025);
WIRE 17 -1 (-1650 1925)(-1650 1975);
WIRE 17 -1 (-1650 1875)(-1650 1925);
WIRE 17 -1 (-1650 1825)(-1650 1875);
WIRE 17 -1 (-1650 1775)(-1650 1825);
WIRE 17 -1 (-1650 1725)(-1650 1775);
WIRE 17 -1 (-1650 1675)(-1650 1725);
WIRE 17 -1 (-1650 1625)(-1650 1675);
WIRE 17 -1 (-1650 1575)(-1650 1625);
WIRE 17 -1 (-1650 1525)(-1650 1575);
WIRE 17 -1 (-1650 1475)(-1650 1525);
WIRE 17 -1 (-3250 3525)(-3250 3575);
WIRE 17 -1 (-3250 3575)(-3250 3600);
WIRE 17 -1 (-3250 3600)(-3800 3600);
FORCEPROP 2 LAST SIG_NAME M_B_BG<1:0>
J 0
(-3750 3610);
DISPLAY 0.617021 (-3750 3610);
PAINT ORANGE (-3750 3610);
WIRE 17 -1 (-3450 3375)(-3450 3450);
WIRE 17 -1 (-3450 3375)(-3450 3275);
WIRE 17 -1 (-3450 3450)(-3950 3450);
FORCEPROP 2 LAST SIG_NAME M_B_CLK_DN<3:0>
J 0
(-3900 3460);
DISPLAY 0.617021 (-3900 3460);
PAINT ORANGE (-3900 3460);
WIRE 17 -1 (-3250 2225)(-3250 2275);
WIRE 17 -1 (-3250 2275)(-3250 2325);
WIRE 17 -1 (-3250 2325)(-3250 2375);
WIRE 17 -1 (-3250 2375)(-3250 2425);
WIRE 17 -1 (-3250 2425)(-3250 2475);
WIRE 17 -1 (-3250 2475)(-3250 2525);
WIRE 17 -1 (-3250 2525)(-3250 2575);
WIRE 17 -1 (-3250 2575)(-3250 2600);
WIRE 17 -1 (-3250 2600)(-3800 2600);
FORCEPROP 2 LAST SIG_NAME M_B_ECC<7:0>
J 0
(-3775 2610);
DISPLAY 0.617021 (-3775 2610);
PAINT ORANGE (-3775 2610);
WIRE 17 -1 (-3250 3700)(-3250 3675);
WIRE 17 -1 (-3250 3700)(-3800 3700);
FORCEPROP 2 LAST SIG_NAME M_B_BA<1:0>
J 0
(-3750 3710);
DISPLAY 0.617021 (-3750 3710);
PAINT ORANGE (-3750 3710);
WIRE 17 -1 (-3250 3325)(-3250 3425);
WIRE 17 -1 (-3250 3425)(-3250 3500);
WIRE 17 -1 (-3250 3500)(-3950 3500);
FORCEPROP 2 LAST SIG_NAME M_B_CLK_DP<3:0>
J 0
(-3900 3510);
DISPLAY 0.617021 (-3900 3510);
PAINT ORANGE (-3900 3510);
WIRE 17 -1 (-3250 3075)(-3250 3125);
WIRE 17 -1 (-3250 3025)(-3250 3075);
WIRE 17 -1 (-3250 3125)(-3250 3150);
WIRE 17 -1 (-3250 3150)(-3800 3150);
FORCEPROP 2 LAST SIG_NAME M_B_CS_N<7:0>
J 0
(-3750 3160);
DISPLAY 0.617021 (-3750 3160);
PAINT ORANGE (-3750 3160);
WIRE 17 -1 (-3250 2975)(-3250 3025);
WIRE 17 -1 (-3250 2875)(-3250 2950);
WIRE 17 -1 (-3250 2825)(-3250 2875);
WIRE 17 -1 (-3250 2950)(-3800 2950);
FORCEPROP 2 LAST SIG_NAME M_B_CKE<3:0>
J 0
(-3775 2960);
DISPLAY 0.617021 (-3775 2960);
PAINT ORANGE (-3775 2960);
WIRE 17 -1 (-3250 3625)(-3250 3675);
WIRE 17 -1 (-3250 2675)(-3250 2725);
WIRE 17 -1 (-3250 2725)(-3250 2800);
WIRE 17 -1 (-3250 2800)(-3800 2800);
FORCEPROP 2 LAST SIG_NAME M_B_ODT<3:0>
J 0
(-3775 2810);
DISPLAY 0.617021 (-3775 2810);
PAINT ORANGE (-3775 2810);
WIRE 16 -1 (-650 2500)(-450 2500);
WIRE 16 -1 (-650 2500)(-650 2550);
WIRE 16 -1 (-650 2550)(-450 2550);
WIRE 16 -1 (-800 2550)(-650 2550);
WIRE 16 -1 (-800 2650)(-800 2550);
WIRE 16 -1 (-650 1150)(-450 1150);
WIRE 16 -1 (-650 1150)(-650 1200);
WIRE 16 -1 (-650 1200)(-450 1200);
WIRE 16 -1 (-650 1200)(-650 1250);
WIRE 16 -1 (-650 1250)(-450 1250);
WIRE 16 -1 (-650 1250)(-650 1300);
WIRE 16 -1 (-650 1300)(-450 1300);
WIRE 16 -1 (-650 1300)(-650 1350);
WIRE 16 -1 (-650 1350)(-450 1350);
WIRE 16 -1 (-650 1350)(-650 1400);
WIRE 16 -1 (-650 1400)(-450 1400);
WIRE 16 -1 (-650 1400)(-650 1450);
WIRE 16 -1 (-650 1450)(-450 1450);
WIRE 16 -1 (-650 1450)(-650 1500);
WIRE 16 -1 (-650 1500)(-450 1500);
WIRE 16 -1 (-650 1500)(-650 1550);
WIRE 16 -1 (-650 1550)(-450 1550);
WIRE 16 -1 (-650 1550)(-650 1600);
WIRE 16 -1 (-650 1600)(-450 1600);
WIRE 16 -1 (-650 1600)(-650 1650);
WIRE 16 -1 (-650 1650)(-450 1650);
WIRE 16 -1 (-650 1650)(-650 1700);
WIRE 16 -1 (-650 1700)(-450 1700);
WIRE 16 -1 (-650 1700)(-650 1750);
WIRE 16 -1 (-650 1750)(-450 1750);
WIRE 16 -1 (-650 1750)(-650 1800);
WIRE 16 -1 (-650 1800)(-450 1800);
WIRE 16 -1 (-650 1800)(-650 1850);
WIRE 16 -1 (-650 1850)(-450 1850);
WIRE 16 -1 (-650 1850)(-650 1900);
WIRE 16 -1 (-650 1900)(-450 1900);
WIRE 16 -1 (-650 1900)(-650 1950);
WIRE 16 -1 (-650 1950)(-450 1950);
WIRE 16 -1 (-650 1950)(-650 2000);
WIRE 16 -1 (-650 2000)(-650 2050);
WIRE 16 -1 (-650 2000)(-450 2000);
WIRE 16 -1 (-650 2050)(-450 2050);
WIRE 16 -1 (-650 2050)(-650 2100);
WIRE 16 -1 (-650 2100)(-450 2100);
WIRE 16 -1 (-650 2100)(-650 2150);
WIRE 16 -1 (-650 2150)(-450 2150);
WIRE 16 -1 (-650 2150)(-650 2200);
WIRE 16 -1 (-650 2200)(-450 2200);
WIRE 16 -1 (-650 2200)(-650 2250);
WIRE 16 -1 (-650 2250)(-450 2250);
WIRE 16 -1 (-650 2250)(-650 2300);
WIRE 16 -1 (-650 2300)(-450 2300);
WIRE 16 -1 (-650 2300)(-650 2350);
WIRE 16 -1 (-650 2350)(-450 2350);
WIRE 16 -1 (-650 2350)(-650 2400);
WIRE 16 -1 (-650 2400)(-450 2400);
WIRE 16 -1 (-1025 2400)(-650 2400);
WIRE 16 -1 (-1025 2500)(-1025 2400);
WIRE 16 -1 (-2950 1750)(-3200 1750);
WIRE 16 -1 (-3200 1750)(-3200 1650);
WIRE 16 -1 (-3200 1650)(-2950 1650);
WIRE 16 -1 (-5050 1650)(-3200 1650);
WIRE 16 -1 (-4600 1150)(-4600 1050);
WIRE 16 -1 (-650 2650)(-450 2650);
WIRE 16 -1 (-650 2700)(-650 2650);
WIRE 16 -1 (-650 2700)(-450 2700);
WIRE 16 -1 (-650 2750)(-650 2700);
WIRE 16 -1 (-650 2750)(-450 2750);
WIRE 16 -1 (-650 2750)(-650 2800);
WIRE 16 -1 (-650 2800)(-450 2800);
WIRE 16 -1 (-650 2850)(-650 2800);
WIRE 16 -1 (-650 2850)(-450 2850);
WIRE 16 -1 (-650 2950)(-650 2850);
WIRE 16 -1 (-2950 1700)(-3125 1700);
WIRE 16 -1 (-3125 1700)(-3125 1800);
WIRE 16 -1 (-2950 1800)(-3125 1800);
WIRE 16 -1 (-3125 1800)(-5050 1800);
WIRE 16 -1 (-5050 1900)(-5050 1800);
WIRE 16 -1 (550 2800)(750 2800);
WIRE 16 -1 (750 2800)(750 2850);
WIRE 16 -1 (550 2850)(750 2850);
WIRE 16 -1 (750 2850)(750 3025);
WIRE 16 -1 (2500 3700)(2500 3750);
WIRE 16 -1 (2500 3650)(2500 3700);
WIRE 16 -1 (2500 3700)(2300 3700);
WIRE 16 -1 (2500 3750)(2300 3750);
WIRE 16 -1 (2500 3600)(2500 3650);
WIRE 16 -1 (2500 3650)(2300 3650);
WIRE 16 -1 (2500 3600)(2300 3600);
WIRE 16 -1 (2500 3550)(2500 3600);
WIRE 16 -1 (2500 3500)(2500 3550);
WIRE 16 -1 (2500 3550)(2300 3550);
WIRE 16 -1 (2500 3450)(2500 3500);
WIRE 16 -1 (2500 3500)(2300 3500);
WIRE 16 -1 (2500 3400)(2500 3450);
WIRE 16 -1 (2500 3450)(2300 3450);
WIRE 16 -1 (2500 3350)(2500 3400);
WIRE 16 -1 (2500 3400)(2300 3400);
WIRE 16 -1 (2500 3300)(2500 3350);
WIRE 16 -1 (2500 3350)(2300 3350);
WIRE 16 -1 (2500 3250)(2500 3300);
WIRE 16 -1 (2500 3300)(2300 3300);
WIRE 16 -1 (2500 3200)(2500 3250);
WIRE 16 -1 (2500 3250)(2300 3250);
WIRE 16 -1 (2500 3150)(2500 3200);
WIRE 16 -1 (2500 3200)(2300 3200);
WIRE 16 -1 (2500 3150)(2500 3100);
WIRE 16 -1 (2500 3150)(2300 3150);
WIRE 16 -1 (2500 3100)(2300 3100);
WIRE 16 -1 (2500 3050)(2500 3100);
WIRE 16 -1 (2500 3050)(2500 3000);
WIRE 16 -1 (2500 3050)(2300 3050);
WIRE 16 -1 (2500 3000)(2500 2950);
WIRE 16 -1 (2500 3000)(2300 3000);
WIRE 16 -1 (2500 2950)(2500 2900);
WIRE 16 -1 (2500 2950)(2300 2950);
WIRE 16 -1 (2500 2900)(2500 2850);
WIRE 16 -1 (2500 2900)(2300 2900);
WIRE 16 -1 (2500 2850)(2500 2800);
WIRE 16 -1 (2500 2850)(2300 2850);
WIRE 16 -1 (2500 2800)(2500 2750);
WIRE 16 -1 (2500 2800)(2300 2800);
WIRE 16 -1 (2500 2750)(2500 2700);
WIRE 16 -1 (2500 2750)(2300 2750);
WIRE 16 -1 (2500 2700)(2500 2650);
WIRE 16 -1 (2500 2700)(2300 2700);
WIRE 16 -1 (2500 2650)(2500 2600);
WIRE 16 -1 (2500 2650)(2300 2650);
WIRE 16 -1 (2500 2600)(2300 2600);
WIRE 16 -1 (2500 2600)(2500 2550);
WIRE 16 -1 (2500 2550)(2500 2500);
WIRE 16 -1 (2500 2550)(2300 2550);
WIRE 16 -1 (2500 2500)(2500 2450);
WIRE 16 -1 (2500 2500)(2300 2500);
WIRE 16 -1 (2500 2450)(2500 2400);
WIRE 16 -1 (2500 2450)(2300 2450);
WIRE 16 -1 (2500 2400)(2500 2350);
WIRE 16 -1 (2500 2400)(2300 2400);
WIRE 16 -1 (2500 2350)(2500 2300);
WIRE 16 -1 (2500 2350)(2300 2350);
WIRE 16 -1 (2500 2300)(2500 2250);
WIRE 16 -1 (2500 2300)(2300 2300);
WIRE 16 -1 (2500 2250)(2500 2200);
WIRE 16 -1 (2500 2250)(2300 2250);
WIRE 16 -1 (2500 2200)(2500 2150);
WIRE 16 -1 (2500 2200)(2300 2200);
WIRE 16 -1 (2500 2150)(2500 2100);
WIRE 16 -1 (2500 2150)(2300 2150);
WIRE 16 -1 (2500 2100)(2500 2050);
WIRE 16 -1 (2500 2100)(2300 2100);
WIRE 16 -1 (2500 2050)(2300 2050);
WIRE 16 -1 (2500 2050)(2500 2000);
WIRE 16 -1 (2500 2000)(2500 1950);
WIRE 16 -1 (2500 2000)(2300 2000);
WIRE 16 -1 (2500 1950)(2500 1900);
WIRE 16 -1 (2500 1950)(2300 1950);
WIRE 16 -1 (2500 1900)(2500 1850);
WIRE 16 -1 (2500 1900)(2300 1900);
WIRE 16 -1 (2500 1850)(2500 1800);
WIRE 16 -1 (2500 1850)(2300 1850);
WIRE 16 -1 (2500 1800)(2500 1750);
WIRE 16 -1 (2500 1800)(2300 1800);
WIRE 16 -1 (2500 1750)(2500 1700);
WIRE 16 -1 (2500 1750)(2300 1750);
WIRE 16 -1 (2500 1700)(2500 1650);
WIRE 16 -1 (2500 1700)(2300 1700);
WIRE 16 -1 (2500 1650)(2500 1600);
WIRE 16 -1 (2500 1650)(2300 1650);
WIRE 16 -1 (2500 1600)(2500 1550);
WIRE 16 -1 (2500 1600)(2300 1600);
WIRE 16 -1 (2500 1550)(2300 1550);
WIRE 16 -1 (2500 1550)(2500 1500);
WIRE 16 -1 (2500 1500)(2500 1450);
WIRE 16 -1 (2500 1500)(2300 1500);
WIRE 16 -1 (2500 1450)(2500 1350);
WIRE 16 -1 (2500 1450)(2300 1450);
WIRE 16 -1 (1100 3750)(1300 3750);
WIRE 16 -1 (1100 3700)(1100 3750);
WIRE 16 -1 (1100 3700)(1300 3700);
WIRE 16 -1 (1100 3650)(1100 3700);
WIRE 16 -1 (1100 3650)(1300 3650);
WIRE 16 -1 (1100 3600)(1100 3650);
WIRE 16 -1 (1100 3600)(1300 3600);
WIRE 16 -1 (1100 3550)(1100 3600);
WIRE 16 -1 (1100 3550)(1300 3550);
WIRE 16 -1 (1100 3500)(1100 3550);
WIRE 16 -1 (1100 3500)(1300 3500);
WIRE 16 -1 (1100 3450)(1100 3500);
WIRE 16 -1 (1100 3450)(1300 3450);
WIRE 16 -1 (1100 3400)(1100 3450);
WIRE 16 -1 (1100 3400)(1300 3400);
WIRE 16 -1 (1100 3350)(1100 3400);
WIRE 16 -1 (1100 3350)(1300 3350);
WIRE 16 -1 (1100 3300)(1100 3350);
WIRE 16 -1 (1100 3300)(1300 3300);
WIRE 16 -1 (1100 3250)(1100 3300);
WIRE 16 -1 (1100 3250)(1300 3250);
WIRE 16 -1 (1100 3200)(1100 3250);
WIRE 16 -1 (1100 3200)(1300 3200);
WIRE 16 -1 (1100 3150)(1100 3200);
WIRE 16 -1 (1100 3150)(1300 3150);
WIRE 16 -1 (1100 3100)(1100 3150);
WIRE 16 -1 (1100 3100)(1300 3100);
WIRE 16 -1 (1100 3050)(1100 3100);
WIRE 16 -1 (1100 3050)(1300 3050);
WIRE 16 -1 (1100 3000)(1100 3050);
WIRE 16 -1 (1100 3000)(1300 3000);
WIRE 16 -1 (1100 2950)(1100 3000);
WIRE 16 -1 (1100 2950)(1300 2950);
WIRE 16 -1 (1100 2900)(1100 2950);
WIRE 16 -1 (1100 2900)(1300 2900);
WIRE 16 -1 (1100 2850)(1100 2900);
WIRE 16 -1 (1100 2850)(1300 2850);
WIRE 16 -1 (1100 2800)(1100 2850);
WIRE 16 -1 (1100 2800)(1300 2800);
WIRE 16 -1 (1100 2750)(1100 2800);
WIRE 16 -1 (1100 2750)(1300 2750);
WIRE 16 -1 (1100 2700)(1100 2750);
WIRE 16 -1 (1100 2700)(1300 2700);
WIRE 16 -1 (1100 2650)(1100 2700);
WIRE 16 -1 (1100 2650)(1300 2650);
WIRE 16 -1 (1100 2600)(1100 2650);
WIRE 16 -1 (1100 2600)(1300 2600);
WIRE 16 -1 (1100 2550)(1100 2600);
WIRE 16 -1 (1100 2550)(1300 2550);
WIRE 16 -1 (1100 2500)(1100 2550);
WIRE 16 -1 (1100 2500)(1300 2500);
WIRE 16 -1 (1100 2450)(1100 2500);
WIRE 16 -1 (1100 2450)(1300 2450);
WIRE 16 -1 (1100 2400)(1100 2450);
WIRE 16 -1 (1100 2400)(1300 2400);
WIRE 16 -1 (1100 2350)(1100 2400);
WIRE 16 -1 (1100 2350)(1300 2350);
WIRE 16 -1 (1100 2300)(1100 2350);
WIRE 16 -1 (1100 2300)(1300 2300);
WIRE 16 -1 (1100 2250)(1100 2300);
WIRE 16 -1 (1100 2250)(1300 2250);
WIRE 16 -1 (1100 2200)(1100 2250);
WIRE 16 -1 (1100 2200)(1300 2200);
WIRE 16 -1 (1100 2150)(1100 2200);
WIRE 16 -1 (1100 2150)(1300 2150);
WIRE 16 -1 (1100 2100)(1100 2150);
WIRE 16 -1 (1100 2100)(1300 2100);
WIRE 16 -1 (1100 2050)(1100 2100);
WIRE 16 -1 (1100 2050)(1300 2050);
WIRE 16 -1 (1100 2000)(1100 2050);
WIRE 16 -1 (1100 2000)(1300 2000);
WIRE 16 -1 (1100 1950)(1100 2000);
WIRE 16 -1 (1100 1950)(1300 1950);
WIRE 16 -1 (1100 1900)(1100 1950);
WIRE 16 -1 (1100 1900)(1300 1900);
WIRE 16 -1 (1100 1850)(1100 1900);
WIRE 16 -1 (1100 1850)(1300 1850);
WIRE 16 -1 (1100 1800)(1100 1850);
WIRE 16 -1 (1100 1800)(1300 1800);
WIRE 16 -1 (1100 1750)(1100 1800);
WIRE 16 -1 (1100 1750)(1300 1750);
WIRE 16 -1 (1100 1700)(1100 1750);
WIRE 16 -1 (1100 1700)(1300 1700);
WIRE 16 -1 (1100 1650)(1100 1700);
WIRE 16 -1 (1100 1650)(1300 1650);
WIRE 16 -1 (1100 1600)(1100 1650);
WIRE 16 -1 (1100 1600)(1300 1600);
WIRE 16 -1 (1100 1550)(1100 1600);
WIRE 16 -1 (1100 1550)(1300 1550);
WIRE 16 -1 (1100 1500)(1100 1550);
WIRE 16 -1 (1100 1500)(1300 1500);
WIRE 16 -1 (1100 1450)(1100 1500);
WIRE 16 -1 (1100 1450)(1300 1450);
WIRE 16 -1 (1100 1350)(1100 1450);
WIRE 16 -1 (-3400 2000)(-3400 2300);
WIRE 16 -1 (-3400 2000)(-2950 2000);
WIRE 16 -1 (-3400 2300)(-4125 2300);
FORCEPROP 2 LAST SIG_NAME FM_DIMM_EVENT_COD_N
J 0
(-4077 2322);
DISPLAY 0.617021 (-4077 2322);
PAINT ORANGE (-4077 2322);
WIRE 16 -1 (-4600 1350)(-4600 1450);
WIRE 16 -1 (-2950 1450)(-4600 1450);
FORCEPROP 2 LAST SIG_NAME M_B_VREF
J 0
(-3750 1460);
DISPLAY 0.617021 (-3750 1460);
PAINT ORANGE (-3750 1460);
WIRE 16 -1 (-4700 1450)(-4600 1450);
WIRE 16 -1 (-3800 1300)(-2950 1300);
FORCEPROP 2 LAST SIG_NAME TP_CH_B_DIMM_B0_RFU_1
J 0
(-3750 1310);
DISPLAY 0.617021 (-3750 1310);
PAINT ORANGE (-3750 1310);
FORCEPROP 2 LASTPROP $XRERR UNIQUE?
J 0
(-4040 1300);
DISPLAY 0.638298 (-4040 1300);
PAINT MONO (-4040 1300);
DISPLAY INVISIBLE (-4040 1300);
WIRE 16 -1 (-3800 1250)(-2950 1250);
FORCEPROP 2 LAST SIG_NAME TP_CH_B_DIMM_B0_RFU_0
J 0
(-3750 1260);
DISPLAY 0.617021 (-3750 1260);
PAINT ORANGE (-3750 1260);
FORCEPROP 2 LASTPROP $XRERR UNIQUE?
J 0
(-4040 1250);
DISPLAY 0.638298 (-4040 1250);
PAINT MONO (-4040 1250);
DISPLAY INVISIBLE (-4040 1250);
WIRE 16 -1 (-3800 1350)(-2950 1350);
FORCEPROP 2 LAST SIG_NAME TP_CH_B_DIMM_B0_RFU_2
J 0
(-3750 1360);
DISPLAY 0.617021 (-3750 1360);
PAINT ORANGE (-3750 1360);
FORCEPROP 2 LASTPROP $XRERR UNIQUE?
J 0
(-4040 1350);
DISPLAY 0.638298 (-4040 1350);
PAINT MONO (-4040 1350);
DISPLAY INVISIBLE (-4040 1350);
WIRE 16 -1 (-2950 1950)(-3975 1950);
FORCEPROP 2 LAST SIG_NAME M_B_ALERT_N
J 0
(-3925 1960);
DISPLAY 0.617021 (-3925 1960);
PAINT ORANGE (-3925 1960);
WIRE 16 -1 (-2950 1900)(-3950 1900);
FORCEPROP 2 LAST SIG_NAME M_B_ACT_N
J 0
(-3900 1910);
DISPLAY 0.617021 (-3900 1910);
PAINT ORANGE (-3900 1910);
WIRE 16 -1 (-2950 1600)(-3800 1600);
WIRE 16 -1 (-3800 1550)(-2950 1550);
FORCEPROP 2 LAST SIG_NAME SMB_DDR_ABC_VPP_SCL
J 0
(-3760 1560);
DISPLAY 0.617021 (-3760 1560);
PAINT ORANGE (-3760 1560);
WIRE 16 -1 (-3800 1150)(-2950 1150);
FORCEPROP 2 LAST SIG_NAME FM_ADR_COMPLETE_ABC_N
J 0
(-3750 1160);
DISPLAY 0.617021 (-3750 1160);
PAINT ORANGE (-3750 1160);
WIRE 16 -1 (-2950 2050)(-3350 2050);
WIRE 16 -1 (-3350 2050)(-3350 2500);
WIRE 16 -1 (-3350 2500)(-3800 2500);
FORCEPROP 2 LAST SIG_NAME M_ABC_RST_N
J 0
(-3775 2510);
DISPLAY 0.617021 (-3775 2510);
PAINT ORANGE (-3775 2510);
WIRE 16 -1 (-2950 2100)(-3300 2100);
WIRE 16 -1 (-3300 2100)(-3300 2550);
WIRE 16 -1 (-3300 2550)(-3800 2550);
FORCEPROP 2 LAST SIG_NAME M_B_PAR
J 0
(-3775 2560);
DISPLAY 0.617021 (-3775 2560);
PAINT ORANGE (-3775 2560);
WIRE 16 -1 (-3100 3150)(-2950 3150);
WIRE 16 -1 (-3100 3200)(-3100 3150);
WIRE 16 -1 (-3100 3200)(-3800 3200);
FORCEPROP 2 LAST SIG_NAME M_B_C<2>
J 0
(-3750 3210);
DISPLAY 0.617021 (-3750 3210);
PAINT ORANGE (-3750 3210);
WIRE 16 -1 (-2950 2950)(-3150 2950);
WIRE 16 -1 (-2950 2800)(-3150 2800);
WIRE 16 -1 (-2950 2700)(-3150 2700);
WIRE 16 -1 (-2950 2650)(-3150 2650);
WIRE 16 -1 (-2950 2550)(-3150 2550);
WIRE 16 -1 (-2950 3850)(-3150 3850);
WIRE 16 -1 (-2950 3600)(-3150 3600);
WIRE 16 -1 (-2950 3550)(-3150 3550);
WIRE 16 -1 (-2950 3400)(-3150 3400);
WIRE 16 -1 (-2950 2850)(-3150 2850);
WIRE 16 -1 (-2950 2250)(-3150 2250);
WIRE 16 -1 (-2950 2300)(-3150 2300);
WIRE 16 -1 (-2950 2350)(-3150 2350);
WIRE 16 -1 (-2950 2400)(-3150 2400);
WIRE 16 -1 (-2950 2450)(-3150 2450);
WIRE 16 -1 (-2950 2500)(-3150 2500);
WIRE 16 -1 (-2950 4050)(-3150 4050);
WIRE 16 -1 (-2950 4000)(-3150 4000);
WIRE 16 -1 (-2950 3950)(-3150 3950);
WIRE 16 -1 (-2950 3900)(-3150 3900);
WIRE 16 -1 (-2950 3800)(-3150 3800);
WIRE 16 -1 (-2950 3750)(-3150 3750);
WIRE 16 -1 (-2950 3000)(-3150 3000);
WIRE 16 -1 (-2950 3050)(-3150 3050);
WIRE 16 -1 (-2950 3100)(-3150 3100);
WIRE 16 -1 (-2950 3300)(-3150 3300);
WIRE 16 -1 (-2950 3650)(-3150 3650);
WIRE 16 -1 (-2950 2200)(-3150 2200);
WIRE 16 -1 (-2950 3250)(-3350 3250);
WIRE 16 -1 (-2950 3350)(-3350 3350);
WIRE 16 -1 (-2950 3500)(-3150 3500);
WIRE 16 -1 (-1750 1450)(-1950 1450);
WIRE 16 -1 (-1750 1500)(-1950 1500);
WIRE 16 -1 (-1750 1700)(-1950 1700);
WIRE 16 -1 (-1750 1650)(-1950 1650);
WIRE 16 -1 (-1750 1600)(-1950 1600);
WIRE 16 -1 (-1750 1550)(-1950 1550);
WIRE 16 -1 (-1750 1750)(-1950 1750);
WIRE 16 -1 (-1750 1850)(-1950 1850);
WIRE 16 -1 (-1750 1900)(-1950 1900);
WIRE 16 -1 (-1750 1950)(-1950 1950);
WIRE 16 -1 (-1750 2000)(-1950 2000);
WIRE 16 -1 (-1750 1800)(-1950 1800);
WIRE 16 -1 (-1750 2300)(-1950 2300);
WIRE 16 -1 (-1750 2200)(-1950 2200);
WIRE 16 -1 (-1750 2050)(-1950 2050);
WIRE 16 -1 (-1750 2100)(-1950 2100);
WIRE 16 -1 (-1750 2150)(-1950 2150);
WIRE 16 -1 (-1750 2250)(-1950 2250);
WIRE 16 -1 (-1750 2350)(-1950 2350);
WIRE 16 -1 (-1750 2400)(-1950 2400);
WIRE 16 -1 (-1750 2500)(-1950 2500);
WIRE 16 -1 (-1750 2550)(-1950 2550);
WIRE 16 -1 (-1750 2450)(-1950 2450);
WIRE 16 -1 (-1750 2750)(-1950 2750);
WIRE 16 -1 (-1750 2800)(-1950 2800);
WIRE 16 -1 (-1750 2600)(-1950 2600);
WIRE 16 -1 (-1750 2650)(-1950 2650);
WIRE 16 -1 (-1750 2700)(-1950 2700);
WIRE 16 -1 (-1750 2950)(-1950 2950);
WIRE 16 -1 (-1750 3000)(-1950 3000);
WIRE 16 -1 (-1750 3050)(-1950 3050);
WIRE 16 -1 (-1750 2850)(-1950 2850);
WIRE 16 -1 (-1750 2900)(-1950 2900);
WIRE 16 -1 (-1750 3350)(-1950 3350);
WIRE 16 -1 (-1750 3250)(-1950 3250);
WIRE 16 -1 (-1750 3200)(-1950 3200);
WIRE 16 -1 (-1750 3100)(-1950 3100);
WIRE 16 -1 (-1750 3150)(-1950 3150);
WIRE 16 -1 (-1750 3300)(-1950 3300);
WIRE 16 -1 (-1750 3400)(-1950 3400);
WIRE 16 -1 (-1750 3450)(-1950 3450);
WIRE 16 -1 (-1750 3500)(-1950 3500);
WIRE 16 -1 (-1750 3550)(-1950 3550);
WIRE 16 -1 (-1750 3800)(-1950 3800);
WIRE 16 -1 (-1750 3850)(-1950 3850);
WIRE 16 -1 (-1750 3900)(-1950 3900);
WIRE 16 -1 (-1750 3950)(-1950 3950);
WIRE 16 -1 (-1750 4000)(-1950 4000);
WIRE 16 -1 (-1750 4050)(-1950 4050);
WIRE 16 -1 (-1750 3600)(-1950 3600);
WIRE 16 -1 (-1750 3650)(-1950 3650);
WIRE 16 -1 (-1750 3700)(-1950 3700);
WIRE 16 -1 (-1750 3750)(-1950 3750);
WIRE 16 -1 (-2950 4550)(-3150 4550);
WIRE 16 -1 (-2950 4500)(-3150 4500);
WIRE 16 -1 (-2950 4450)(-3150 4450);
WIRE 16 -1 (-2950 4300)(-3150 4300);
WIRE 16 -1 (-2950 4250)(-3150 4250);
WIRE 16 -1 (-2950 4200)(-3150 4200);
WIRE 16 -1 (-2950 4150)(-3150 4150);
WIRE 16 -1 (-2950 4100)(-3150 4100);
WIRE 16 -1 (-2950 4600)(-3150 4600);
WIRE 16 -1 (-2950 4400)(-3150 4400);
WIRE 16 -1 (-2950 4350)(-3150 4350);
WIRE 16 -1 (-1750 4600)(-1950 4600);
WIRE 16 -1 (-1750 4550)(-1950 4550);
WIRE 16 -1 (-1750 4500)(-1950 4500);
WIRE 16 -1 (-1750 4100)(-1950 4100);
WIRE 16 -1 (-1750 4150)(-1950 4150);
WIRE 16 -1 (-1750 4350)(-1950 4350);
WIRE 16 -1 (-1750 4300)(-1950 4300);
WIRE 16 -1 (-1750 4200)(-1950 4200);
WIRE 16 -1 (-1750 4250)(-1950 4250);
WIRE 16 -1 (-1750 4400)(-1950 4400);
WIRE 16 -1 (-1750 4450)(-1950 4450);
WIRE 16 -1 (650 4050)(450 4050);
WIRE 16 -1 (850 4000)(450 4000);
WIRE 16 -1 (650 3950)(450 3950);
WIRE 16 -1 (850 3900)(450 3900);
WIRE 16 -1 (650 3850)(450 3850);
WIRE 16 -1 (850 3800)(450 3800);
WIRE 16 -1 (650 3750)(450 3750);
WIRE 16 -1 (850 3700)(450 3700);
WIRE 16 -1 (450 3650)(650 3650);
WIRE 16 -1 (450 3600)(850 3600);
WIRE 16 -1 (450 3550)(650 3550);
WIRE 16 -1 (450 3500)(850 3500);
WIRE 16 -1 (450 3450)(650 3450);
WIRE 16 -1 (450 3400)(850 3400);
WIRE 16 -1 (650 4350)(450 4350);
WIRE 16 -1 (850 4300)(450 4300);
WIRE 16 -1 (650 4250)(450 4250);
WIRE 16 -1 (850 4200)(450 4200);
WIRE 16 -1 (650 4150)(450 4150);
WIRE 16 -1 (850 4100)(450 4100);
WIRE 16 -1 (850 5100)(450 5100);
WIRE 16 -1 (650 5050)(450 5050);
WIRE 16 -1 (850 5000)(450 5000);
WIRE 16 -1 (650 4950)(450 4950);
WIRE 16 -1 (850 4900)(450 4900);
WIRE 16 -1 (650 4850)(450 4850);
WIRE 16 -1 (850 4800)(450 4800);
WIRE 16 -1 (650 4750)(450 4750);
WIRE 16 -1 (850 4700)(450 4700);
WIRE 16 -1 (650 4650)(450 4650);
WIRE 16 -1 (850 4600)(450 4600);
WIRE 16 -1 (650 4550)(450 4550);
WIRE 16 -1 (850 4500)(450 4500);
WIRE 16 -1 (650 4450)(450 4450);
WIRE 16 -1 (850 4400)(450 4400);
WIRE 16 -1 (650 5150)(450 5150);
DOT 1 (1100 2550);
DOT 1 (-3200 1650);
DOT 1 (-650 2300);
DOT 1 (-650 1200);
DOT 1 (-650 2550);
DOT 1 (-650 1250);
DOT 1 (-650 1300);
DOT 1 (-650 1350);
DOT 1 (-650 1400);
DOT 1 (-650 1450);
DOT 1 (-650 1550);
DOT 1 (-650 1500);
DOT 1 (-650 1600);
DOT 1 (-650 1650);
DOT 1 (-650 1700);
DOT 1 (-650 1800);
DOT 1 (-650 1750);
DOT 1 (-650 1850);
DOT 1 (-650 1900);
DOT 1 (-650 1950);
DOT 1 (-650 2050);
DOT 1 (-650 2000);
DOT 1 (-650 2150);
DOT 1 (-650 2200);
DOT 1 (-650 2250);
DOT 1 (-650 2750);
DOT 1 (-650 2850);
DOT 1 (2500 3700);
DOT 1 (2500 3650);
DOT 1 (2500 3600);
DOT 1 (2500 3550);
DOT 1 (2500 3500);
DOT 1 (2500 3450);
DOT 1 (1100 3700);
DOT 1 (1100 3650);
DOT 1 (1100 3550);
DOT 1 (1100 3500);
DOT 1 (1100 3450);
DOT 1 (1100 3400);
DOT 1 (2500 3400);
DOT 1 (2500 3300);
DOT 1 (2500 3350);
DOT 1 (2500 3150);
DOT 1 (2500 3050);
DOT 1 (2500 3100);
DOT 1 (2500 3000);
DOT 1 (2500 2950);
DOT 1 (2500 2900);
DOT 1 (2500 2800);
DOT 1 (2500 2700);
DOT 1 (2500 2650);
DOT 1 (2500 2600);
DOT 1 (2500 2550);
DOT 1 (2500 2500);
DOT 1 (2500 2450);
DOT 1 (2500 2400);
DOT 1 (2500 2350);
DOT 1 (2500 2300);
DOT 1 (2500 2250);
DOT 1 (2500 2200);
DOT 1 (2500 2150);
DOT 1 (2500 2100);
DOT 1 (2500 2050);
DOT 1 (2500 2000);
DOT 1 (2500 1900);
DOT 1 (2500 1950);
DOT 1 (2500 1850);
DOT 1 (2500 1800);
DOT 1 (2500 1750);
DOT 1 (2500 1700);
DOT 1 (2500 1650);
DOT 1 (2500 1600);
DOT 1 (2500 1550);
DOT 1 (2500 1500);
DOT 1 (2500 1450);
DOT 1 (1100 3300);
DOT 1 (1100 3350);
DOT 1 (1100 3250);
DOT 1 (1100 3200);
DOT 1 (1100 3150);
DOT 1 (1100 3050);
DOT 1 (1100 3100);
DOT 1 (1100 3000);
DOT 1 (1100 2950);
DOT 1 (1100 2900);
DOT 1 (1100 2800);
DOT 1 (1100 2850);
DOT 1 (1100 2750);
DOT 1 (1100 2700);
DOT 1 (1100 2650);
DOT 1 (1100 2600);
DOT 1 (1100 2450);
DOT 1 (1100 2400);
DOT 1 (1100 2350);
DOT 1 (1100 2300);
DOT 1 (1100 2250);
DOT 1 (1100 2200);
DOT 1 (1100 2150);
DOT 1 (1100 2100);
DOT 1 (1100 2050);
DOT 1 (1100 2000);
DOT 1 (1100 1950);
DOT 1 (1100 1900);
DOT 1 (1100 1850);
DOT 1 (1100 1800);
DOT 1 (1100 1750);
DOT 1 (1100 1700);
DOT 1 (1100 1600);
DOT 1 (1100 1550);
DOT 1 (1100 1500);
DOT 1 (1100 1450);
DOT 1 (2500 2850);
DOT 1 (-4600 1450);
DOT 1 (2500 3250);
DOT 1 (2500 3200);
DOT 1 (2500 2750);
DOT 1 (1100 2500);
DOT 1 (-3125 1800);
DOT 1 (1100 3600);
DOT 1 (750 2850);
DOT 1 (-650 2400);
DOT 1 (-650 2100);
DOT 1 (-650 2700);
DOT 1 (-650 2800);
DOT 1 (-650 2350);
DOT 1 (1100 1650);
FORCENOTE
PLACE CAP NEAR DIMM CONNECTOR
(-5304 900) 0;
DISPLAY LEFT (-5304 900);
DISPLAY 1.595745 (-5304 900);
PAINT PURPLE (-5304 900);
FORCENOTE
SMBUS ADDR: 0XA4
(-5317 737) 0;
DISPLAY LEFT (-5317 737);
DISPLAY 1.957447 (-5317 737);
PAINT PURPLE (-5317 737);
QUIT
